# Lightning_PDPB_Pick & place.xlsx — Sheet1 (pick-and-place)
| 15669-1.1115WPH1657.brd |  |  |  |  |  |  |  |  |
| Date  Tue Mar 07 17:40:21 2017 |  |  |  |  |  |  |  |  |
| Total Components:  1140 |  |  |  |  |  |  |  |  |
| Component Report |  |  |  |  |  |  |  |  |
| REFDES | COMP_DEVICE_TYPE | COMP_VALUE | COMP_TOL | COMP_PACKAGE | SYM_X | SYM_Y | SYM_ROTATE | SYM_MIRROR |
| C110 | C402H22 | SC1KP50V2KX-1GP | 78.10224.2FL | C402H22 | 4175 | 17120 | 180 | NO |
| C111 | C402H22 | SC1KP50V2KX-1GP | 78.10224.2FL | C402H22 | 4175 | 17200 | 180 | NO |
| C131 | C402H22 | SC1KP50V2KX-1GP | 78.10224.2FL | C402H22 | 3465 | 16525 | 90 | NO |
| C132 | C402H22 | SC1KP50V2KX-1GP | 78.10224.2FL | C402H22 | 3545 | 16525 | 90 | NO |
| C341 | C402H22 | SCD1U16V2KX-3GP | 78.10421.2FL | C402H22 | 8330 | 18170 | 270 | NO |
| C342 | C402H22 | SCD1U16V2KX-3GP | 78.10421.2FL | C402H22 | 8330 | 2030 | 270 | NO |
| C343 | C402H22 | SCD1U16V2KX-3GP | 78.10421.2FL | C402H22 | 1265 | 15020 | 270 | NO |
| C344 | C402H22 | SCD1U16V2KX-3GP | 78.10421.2FL | C402H22 | 1790 | 5535 | 270 | NO |
| C346 | C603H36 | SC1U16V3KX-5GP | 78.10521.2BL | C603H36 | 2880 | 17490 | 0 | NO |
| C347 | C603H36 | SCD1U50V3KX-GP | 78.10424.2BL | C603H36 | 2930 | 17490 | 0 | NO |
| C348 | C1206-TO0D3H75 | SC22U25V6KX-GP-U | 078.22622.082N | C1206-TO0D3H75 | 9732 | 14197 | 0 | NO |
| C349 | C1206-TO0D3H75 | SC22U25V6KX-GP-U | 078.22622.082N | C1206-TO0D3H75 | 9607 | 14197 | 0 | NO |
| C352 | C402H22 | SCD1U16V2KX-3GP | 78.10421.2FL | C402H22 | 3590 | 1205 | 270 | NO |
| C355 | C603H36 | SC220P50V3JN-GP | 78.22134.1BL | C603H36 | 9665 | 16610 | 270 | NO |
| C356 | C603H36 | SC220P50V3JN-GP | 78.22134.1BL | C603H36 | 9665 | 16710 | 270 | NO |
| C357 | C402H22 | SCD1U16V2KX-3GP | 78.10421.2FL | C402H22 | 3655 | 765 | 270 | NO |
| C358 | C402H22 | SCD1U16V2KX-3GP | 78.10421.2FL | C402H22 | 3735 | 1030 | 0 | NO |
| C359 | C402H22 | SCD1U16V2KX-3GP | 78.10421.2FL | C402H22 | 3743 | 864 | 0 | NO |
| C363 | C402H22 | SC1U10V2KX-7-GP | 078.10523.08FV | C402H22 | 3590 | 1170 | 270 | NO |
| C382 | C402H22 | SCD1U25V2KX-2-GP | 78.10422.2FL | C402H22 | 7928.39 | 19335.07 | 0 | NO |
| C383 | C402H22 | SCD1U25V2KX-2-GP | 78.10422.2FL | C402H22 | 8280 | 15595 | 0 | NO |
| C384 | C402H22 | SCD1U25V2KX-2-GP | 78.10422.2FL | C402H22 | 8280 | 11540 | 0 | NO |
| C385 | C402H22 | SCD1U25V2KX-2-GP | 78.10422.2FL | C402H22 | 8280 | 7485 | 0 | NO |
| C386 | C402H22 | SCD1U25V2KX-2-GP | 78.10422.2FL | C402H22 | 8280 | 3430 | 0 | NO |
| C387 | C402H22 | SCD1U25V2KX-2-GP | 78.10422.2FL | C402H22 | 695 | 19345 | 0 | NO |
| C388 | C402H22 | SCD1U25V2KX-2-GP | 78.10422.2FL | C402H22 | 990 | 15505 | 0 | NO |
| C389 | C402H22 | SCD1U25V2KX-2-GP | 78.10422.2FL | C402H22 | 997 | 11544 | 0 | NO |
| C390 | C402H22 | SCD1U25V2KX-2-GP | 78.10422.2FL | C402H22 | 997 | 7485 | 0 | NO |
| C391 | C402H22 | SCD1U25V2KX-2-GP | 78.10422.2FL | C402H22 | 997 | 3430 | 0 | NO |
| C392 | C402H22 | SCD1U25V2KX-2-GP | 78.10422.2FL | C402H22 | 1459 | 16491 | 180 | NO |
| C393 | C402H22 | SCD1U25V2KX-2-GP | 78.10422.2FL | C402H22 | 1447 | 12436 | 180 | NO |
| C394 | C402H22 | SCD1U25V2KX-2-GP | 78.10422.2FL | C402H22 | 1444 | 8381 | 180 | NO |
| C395 | C402H22 | SCD1U25V2KX-2-GP | 78.10422.2FL | C402H22 | 1444 | 4326 | 180 | NO |
| C396 | C402H22 | SCD1U25V2KX-2-GP | 78.10422.2FL | C402H22 | 1930 | 585 | 180 | NO |
| C939 | C402H22 | SC1KP50V2KX-1GP | 78.10224.2FL | C402H22 | 3820 | 11540 | 90 | NO |
| C940 | C402H22 | SC1KP50V2KX-1GP | 78.10224.2FL | C402H22 | 3900 | 11540 | 90 | NO |
| C8837 | C402H22 | SCD1U16V2KX-3GP | 78.10421.2FL | C402H22 | 3760 | 16720 | 0 | NO |
| C8838 | C402H22 | SCD1U16V2KX-3GP | 78.10421.2FL | C402H22 | 3870 | 16765 | 90 | NO |
| C8839 | C402H22 | SCD1U16V2KX-3GP | 78.10421.2FL | C402H22 | 3725 | 17295 | 180 | NO |
| C8840 | C402H22 | SCD1U16V2KX-3GP | 78.10421.2FL | C402H22 | 3880 | 17235 | 90 | NO |
| C8849 | C402H22 | SCD1U16V2KX-3GP | 78.10421.2FL | C402H22 | 3710 | 11730 | 0 | NO |
| C8850 | C402H22 | SCD1U16V2KX-3GP | 78.10421.2FL | C402H22 | 3935 | 11795 | 180 | NO |
| C8851 | C402H22 | SCD1U16V2KX-3GP | 78.10421.2FL | C402H22 | 3720 | 12315 | 180 | NO |
| C8852 | C402H22 | SCD1U16V2KX-3GP | 78.10421.2FL | C402H22 | 3935 | 12235 | 0 | NO |
| C8861 | C402H22 | SCD1U16V2KX-3GP | 78.10421.2FL | C402H22 | 3720 | 8600 | 180 | NO |
| C8862 | C402H22 | SCD1U16V2KX-3GP | 78.10421.2FL | C402H22 | 3935 | 8465 | 0 | NO |
| C8863 | C402H22 | SCD1U16V2KX-3GP | 78.10421.2FL | C402H22 | 3900 | 8065 | 90 | NO |
| C8864 | C402H22 | SCD1U16V2KX-3GP | 78.10421.2FL | C402H22 | 3655 | 8020 | 0 | NO |
| C8873 | C402H22 | SCD1U16V2KX-3GP | 78.10421.2FL | C402H22 | 3720 | 4310 | 180 | NO |
| C8874 | C402H22 | SCD1U16V2KX-3GP | 78.10421.2FL | C402H22 | 3935 | 4165 | 0 | NO |
| C8875 | C402H22 | SCD1U16V2KX-3GP | 78.10421.2FL | C402H22 | 3935 | 3820 | 180 | NO |
| C8876 | C402H22 | SCD1U16V2KX-3GP | 78.10421.2FL | C402H22 | 3720 | 3695 | 0 | NO |
| C8893 | C402H22 | SC1U10V2KX-7-GP | 078.10523.08FV | C402H22 | 3430 | 17185 | 0 | NO |
| C8894 | C402H22 | SCD1U16V2KX-3GP | 78.10421.2FL | C402H22 | 3465 | 17185 | 0 | NO |
| C8895 | C402H22 | SC1U10V2KX-7-GP | 078.10523.08FV | C402H22 | 3410 | 17045 | 180 | NO |
| C8896 | C402H22 | SCD1U16V2KX-3GP | 78.10421.2FL | C402H22 | 3445 | 17045 | 180 | NO |
| C8897 | C603H40 | SC10U25V3MX-GP | 78.10612.5BL | C603H40 | 3120 | 17157 | 270 | NO |
| C8909 | C402H22 | SC1U10V2KX-7-GP | 078.10523.08FV | C402H22 | 3430 | 12200 | 0 | NO |
| C8910 | C402H22 | SCD1U16V2KX-3GP | 78.10421.2FL | C402H22 | 3465 | 12200 | 0 | NO |
| C8911 | C402H22 | SC1U10V2KX-7-GP | 078.10523.08FV | C402H22 | 3410 | 12060 | 180 | NO |
| C8912 | C402H22 | SCD1U16V2KX-3GP | 78.10421.2FL | C402H22 | 3445 | 12060 | 180 | NO |
| C8913 | C402H22 | SC1U10V2KX-7-GP | 078.10523.08FV | C402H22 | 3430 | 8485 | 0 | NO |
| C8914 | C603H40 | SC10U25V3MX-GP | 78.10612.5BL | C603H40 | 3110 | 12175 | 270 | NO |
| C8915 | C402H22 | SCD1U16V2KX-3GP | 78.10421.2FL | C402H22 | 3465 | 8485 | 0 | NO |
| C8916 | C402H22 | SC1U10V2KX-7-GP | 078.10523.08FV | C402H22 | 3410 | 8345 | 180 | NO |
| C8929 | C402H22 | SCD1U16V2KX-3GP | 78.10421.2FL | C402H22 | 3445 | 8345 | 180 | NO |
| C8930 | C603H40 | SC10U25V3MX-GP | 78.10612.5BL | C603H40 | 3109 | 8467 | 270 | NO |
| C8931 | C402H22 | SC1U10V2KX-7-GP | 078.10523.08FV | C402H22 | 3430 | 4185 | 0 | NO |
| C8932 | C402H22 | SCD1U16V2KX-3GP | 78.10421.2FL | C402H22 | 3465 | 4185 | 0 | NO |
| C8933 | C402H22 | SC1U10V2KX-7-GP | 078.10523.08FV | C402H22 | 3410 | 4045 | 180 | NO |
| C8934 | C402H22 | SCD1U16V2KX-3GP | 78.10421.2FL | C402H22 | 3445 | 4045 | 180 | NO |
| C8935 | C603H40 | SC10U25V3MX-GP | 78.10612.5BL | C603H40 | 3109 | 4162 | 270 | NO |
| C9321 | C603H36 | SCD1U25V3KX-GP | 78.10422.2BL | C603H36 | 2976 | 13985 | 0 | NO |
| C9322 | C603H36 | SCD1U25V3KX-GP | 78.10422.2BL | C603H36 | 3231 | 5834 | 90 | NO |
| C9337 | C402H22 | SC1KP50V2KX-1GP | 78.10224.2FL | C402H22 | 3465 | 3525 | 90 | NO |
| C9339 | C402H22 | SC1KP50V2KX-1GP | 78.10224.2FL | C402H22 | 3545 | 3525 | 90 | NO |
| C9341 | C402H22 | SC1KP50V2KX-1GP | 78.10224.2FL | C402H22 | 3755 | 7825 | 90 | NO |
| C9343 | C402H22 | SC1KP50V2KX-1GP | 78.10224.2FL | C402H22 | 3535 | 17475 | 270 | NO |
| C9345 | C402H22 | SC1KP50V2KX-1GP | 78.10224.2FL | C402H22 | 3535 | 4475 | 270 | NO |
| C9347 | C402H22 | SC1KP50V2KX-1GP | 78.10224.2FL | C402H22 | 3890 | 4475 | 270 | NO |
| C9349 | C402H22 | SC1KP50V2KX-1GP | 78.10224.2FL | C402H22 | 3535 | 12490 | 270 | NO |
| C9351 | C402H22 | SC1KP50V2KX-1GP | 78.10224.2FL | C402H22 | 4175 | 8110 | 180 | NO |
| C9353 | C402H22 | SC1KP50V2KX-1GP | 78.10224.2FL | C402H22 | 4175 | 12135 | 180 | NO |
| C9355 | C402H22 | SC1KP50V2KX-1GP | 78.10224.2FL | C402H22 | 3820 | 3525 | 90 | NO |
| C9357 | C402H22 | SC1KP50V2KX-1GP | 78.10224.2FL | C402H22 | 3890 | 8775 | 270 | NO |
| C9359 | C402H22 | SC1KP50V2KX-1GP | 78.10224.2FL | C402H22 | 3890 | 12490 | 270 | NO |
| C9361 | C402H22 | SC1KP50V2KX-1GP | 78.10224.2FL | C402H22 | 3535 | 8775 | 270 | NO |
| C9363 | C402H22 | SC1KP50V2KX-1GP | 78.10224.2FL | C402H22 | 4175 | 8190 | 180 | NO |
| C9365 | C402H22 | SC1KP50V2KX-1GP | 78.10224.2FL | C402H22 | 4175 | 12215 | 180 | NO |
| C9366 | C402H22 | SC1KP50V2KX-1GP | 78.10224.2FL | C402H22 | 3835 | 7825 | 90 | NO |
| C9367 | C402H22 | SC1KP50V2KX-1GP | 78.10224.2FL | C402H22 | 3455 | 17475 | 270 | NO |
| C9368 | C402H22 | SC1KP50V2KX-1GP | 78.10224.2FL | C402H22 | 3810 | 12490 | 270 | NO |
| C9369 | C402H22 | SC1KP50V2KX-1GP | 78.10224.2FL | C402H22 | 3810 | 8775 | 270 | NO |
| C9370 | C402H22 | SC1KP50V2KX-1GP | 78.10224.2FL | C402H22 | 3810 | 4475 | 270 | NO |
| C9371 | C402H22 | SC1KP50V2KX-1GP | 78.10224.2FL | C402H22 | 3455 | 12490 | 270 | NO |
| C9372 | C402H22 | SC1KP50V2KX-1GP | 78.10224.2FL | C402H22 | 3455 | 8775 | 270 | NO |
| C9373 | C402H22 | SC1KP50V2KX-1GP | 78.10224.2FL | C402H22 | 3455 | 4475 | 270 | NO |
| C9374 | C402H22 | SC1KP50V2KX-1GP | 78.10224.2FL | C402H22 | 3900 | 3525 | 90 | NO |
| C9418 | C402H22 | SCD1U16V2KX-3GP | 78.10421.2FL | C402H22 | 3690 | 17295 | 180 | NO |
| C9419 | C402H22 | SCD1U16V2KX-3GP | 78.10421.2FL | C402H22 | 3957 | 16990 | 180 | NO |
| C9424 | C402H22 | SCD1U16V2KX-3GP | 78.10421.2FL | C402H22 | 3675 | 11730 | 0 | NO |
| C9425 | C402H22 | SCD1U16V2KX-3GP | 78.10421.2FL | C402H22 | 3685 | 12315 | 180 | NO |
| C9428 | C402H22 | SCD1U16V2KX-3GP | 78.10421.2FL | C402H22 | 3685 | 8600 | 180 | NO |
| C9429 | C402H22 | SCD1U16V2KX-3GP | 78.10421.2FL | C402H22 | 3620 | 8020 | 0 | NO |
| C9432 | C402H22 | SCD1U16V2KX-3GP | 78.10421.2FL | C402H22 | 3956 | 3999 | 180 | NO |
| C9433 | C402H22 | SCD1U16V2KX-3GP | 78.10421.2FL | C402H22 | 3685 | 4310 | 180 | NO |
| C9514 | C402H22 | SCD1U16V2KX-3GP | 78.10421.2FL | C402H22 | 3725 | 16720 | 0 | NO |
| C9515 | C402H22 | SCD1U16V2KX-3GP | 78.10421.2FL | C402H22 | 3956 | 12005 | 180 | NO |
| C9516 | C402H22 | SCD1U16V2KX-3GP | 78.10421.2FL | C402H22 | 3935 | 8315 | 180 | NO |
| C9517 | C402H22 | SCD1U16V2KX-3GP | 78.10421.2FL | C402H22 | 3685 | 3695 | 0 | NO |
| C9518 | C402H22 | SCD1U16V2KX-3GP | 78.10421.2FL | C402H22 | 9042.4 | 17603.099999999999 | 0 | NO |
| C9519 | C402H22 | SCD1U16V2KX-3GP | 78.10421.2FL | C402H22 | 9042.4 | 13547.98 | 0 | NO |
| C9520 | C402H22 | SCD1U16V2KX-3GP | 78.10421.2FL | C402H22 | 9042.4 | 9492.8700000000008 | 0 | NO |
| C9521 | C402H22 | SCD1U16V2KX-3GP | 78.10421.2FL | C402H22 | 9042.4 | 5437.75 | 0 | NO |
| C9522 | C402H22 | SCD1U16V2KX-3GP | 78.10421.2FL | C402H22 | 9052.4 | 1382.63 | 0 | NO |
| C9523 | C402H22 | SCD1U16V2KX-3GP | 78.10421.2FL | C402H22 | 1946.06 | 17711.900000000001 | 180 | NO |
| C9524 | C402H22 | SCD1U16V2KX-3GP | 78.10421.2FL | C402H22 | 1758.94 | 13547.98 | 0 | NO |
| C9525 | C402H22 | SCD1U16V2KX-3GP | 78.10421.2FL | C402H22 | 1820 | 9545 | 0 | NO |
| C9526 | C402H22 | SCD1U16V2KX-3GP | 78.10421.2FL | C402H22 | 1535 | 5695 | 90 | NO |
| C9527 | C402H22 | SCD1U16V2KX-3GP | 78.10421.2FL | C402H22 | 1758.94 | 1396.63 | 0 | NO |
| C9528 | C402H22 | SCD1U16V2KX-3GP | 78.10421.2FL | C402H22 | 783.87 | 18542.68 | 270 | NO |
| C9529 | C402H22 | SCD1U16V2KX-3GP | 78.10421.2FL | C402H22 | 827.48 | 14601.48 | 180 | NO |
| C9530 | C402H22 | SCD1U16V2KX-3GP | 78.10421.2FL | C402H22 | 832.48 | 10546.36 | 180 | NO |
| C9531 | C402H22 | SCD1U16V2KX-3GP | 78.10421.2FL | C402H22 | 820 | 6510 | 180 | NO |
| C9532 | C402H22 | SCD1U16V2KX-3GP | 78.10421.2FL | C402H22 | 820 | 2454.88 | 180 | NO |
| C9533 | C402H22 | SCD01U50V2KX-1GP | 78.10324.2FL | C402H22 | 9946 | 14193 | 0 | NO |
| C9534 | C402H22 | SCD01U50V2KX-1GP | 78.10324.2FL | C402H22 | 266 | 14901 | 180 | NO |
| C9535 | C402H22 | SCD01U50V2KX-1GP | 78.10324.2FL | C402H22 | 302 | 14901 | 180 | NO |
| C9536 | C402H22 | SCD01U50V2KX-1GP | 78.10324.2FL | C402H22 | 363.5 | 15122 | 180 | NO |
| C9537 | C402H22 | SCD01U50V2KX-1GP | 78.10324.2FL | C402H22 | 328.5 | 15122 | 180 | NO |
| C9538 | C402H22 | SCD01U50V2KX-1GP | 78.10324.2FL | C402H22 | 583.72 | 16765.48 | 180 | NO |
| C9539 | C402H22 | SCD01U50V2KX-1GP | 78.10324.2FL | C402H22 | 548.72 | 16765.48 | 180 | NO |
| C9540 | C402H22 | SCD01U50V2KX-1GP | 78.10324.2FL | C402H22 | 312 | 17753.5 | 270 | NO |
| C9541 | C402H22 | SCD01U50V2KX-1GP | 78.10324.2FL | C402H22 | 312 | 17788.5 | 270 | NO |
| CN7 | GPCE54362413HR | AMP-CONN60-5-GP | 20.F2288.060 | GPCE54362413HR | 10232.280000000001 | 16139.76 | 90 | NO |
| D18 | SOD323AKH44 | RB551V30-1-GP | 083.55130.008F | SOD323AKH44 | 7778.39 | 19430.07 | 0 | NO |
| D19 | SOD323AKH44 | RB551V30-1-GP | 083.55130.008F | SOD323AKH44 | 8130 | 15690 | 0 | NO |
| D20 | SOD323AKH44 | RB551V30-1-GP | 083.55130.008F | SOD323AKH44 | 8130 | 11635 | 0 | NO |
| D21 | SOD323AKH44 | RB551V30-1-GP | 083.55130.008F | SOD323AKH44 | 8130 | 7580 | 0 | NO |
| D22 | SOD323AKH44 | RB551V30-1-GP | 083.55130.008F | SOD323AKH44 | 8130 | 3525 | 0 | NO |
| D23 | SOD323AKH44 | RB551V30-1-GP | 083.55130.008F | SOD323AKH44 | 545 | 19440 | 0 | NO |
| D24 | SOD323AKH44 | RB551V30-1-GP | 083.55130.008F | SOD323AKH44 | 840 | 15600 | 0 | NO |
| D25 | SOD323AKH44 | RB551V30-1-GP | 083.55130.008F | SOD323AKH44 | 847 | 11639 | 0 | NO |
| D26 | SOD323AKH44 | RB551V30-1-GP | 083.55130.008F | SOD323AKH44 | 847 | 7580 | 0 | NO |
| D27 | SOD323AKH44 | RB551V30-1-GP | 083.55130.008F | SOD323AKH44 | 847 | 3525 | 0 | NO |
| D28 | SOD323AKH44 | RB551V30-1-GP | 083.55130.008F | SOD323AKH44 | 1609 | 16396 | 180 | NO |
| D29 | SOD323AKH44 | RB551V30-1-GP | 083.55130.008F | SOD323AKH44 | 1597 | 12341 | 180 | NO |
| D30 | SOD323AKH44 | RB551V30-1-GP | 083.55130.008F | SOD323AKH44 | 1594 | 8286 | 180 | NO |
| D31 | SOD323AKH44 | RB551V30-1-GP | 083.55130.008F | SOD323AKH44 | 1594 | 4231 | 180 | NO |
| D32 | SOD323AKH44 | RB551V30-1-GP | 083.55130.008F | SOD323AKH44 | 2080 | 490 | 180 | NO |
| EU1 | QFN64G9-G6D25H40 | 9ZXL1231AKLFT-GP | 071.91231.0003 | QFN64G9-G6D25H40 | 3700 | 17000 | 90 | NO |
| EU2 | QFN64G9-G6D25H40 | 9ZXL1231AKLFT-GP | 071.91231.0003 | QFN64G9-G6D25H40 | 3700 | 12015 | 90 | NO |
| EU3 | QFN64G9-G6D25H40 | 9ZXL1231AKLFT-GP | 071.91231.0003 | QFN64G9-G6D25H40 | 3700 | 8300 | 90 | NO |
| EU4 | QFN64G9-G6D25H40 | 9ZXL1231AKLFT-GP | 071.91231.0003 | QFN64G9-G6D25H40 | 3700 | 4000 | 90 | NO |
| EU16 | QFN24-G2D25H40 | PCA9547BS-GP | 071.09547.0003 | QFN24-G2D25H40 | 3000 | 5855 | 0 | NO |
| EU17 | QFN24-G2D25H40 | PCA9547BS-GP | 071.09547.0003 | QFN24-G2D25H40 | 3000 | 14215 | 270 | NO |
| FB6 | L805H42 | BLM21PG331SN1D-2-GP | 68.00084.571 | L805H42 | 3115 | 17221 | 90 | NO |
| FB7 | L805H42 | BLM21PG331SN1D-2-GP | 68.00084.571 | L805H42 | 3110 | 12240 | 90 | NO |
| FB9 | L805H42 | BLM21PG331SN1D-2-GP | 68.00084.571 | L805H42 | 3117 | 8531 | 90 | NO |
| FB10 | L805H42 | BLM21PG331SN1D-2-GP | 68.00084.571 | L805H42 | 3114 | 4226 | 90 | NO |
| H1 | GEN276X162R197X296-6-F-A | GEN276X162R197X296-6-F-A-GP | ZZ.SCREW.511 | GEN276X162R197X296-6-F-A | 216.54 | 19228.349999999999 | 0 | NO |
| H2 | GEN276X162R197X296-6-F-A | GEN276X162R197X296-6-F-A-GP | ZZ.SCREW.511 | GEN276X162R197X296-6-F-A | 2755.91 | 19035.34 | 0 | NO |
| H3 | HOLE315R140 | HOLE315R140-GP | ZZ.00PAD.KZ1 | HOLE315R140 | 2696.85 | 14901.57 | 0 | NO |
| H4 | GEN276X162R197X296-6-F-A | GEN276X162R197X296-6-F-A-GP | ZZ.SCREW.511 | GEN276X162R197X296-6-F-A | 2755.91 | 10885.73 | 0 | NO |
| H5 | GEN276X162R197X296-6-F-A | GEN276X162R197X296-6-F-A-GP | ZZ.SCREW.511 | GEN276X162R197X296-6-F-A | 9980.31 | 10826.67 | 0 | NO |
| H6 | HOLE315R140 | HOLE315R140-GP | ZZ.00PAD.KZ1 | HOLE315R140 | 334.64 | 10295.280000000001 | 0 | NO |
| H7 | GEN276X162R197X296-6-F-A | GEN276X162R197X296-6-F-A-GP | ZZ.SCREW.511 | GEN276X162R197X296-6-F-A | 2755.91 | 6850.3 | 0 | NO |
| H8 | GEN276X162R197X296-6-F-A | GEN276X162R197X296-6-F-A-GP | ZZ.SCREW.511 | GEN276X162R197X296-6-F-A | 9980.31 | 6869.98 | 0 | NO |
| H9 | GEN276X162R197X296-6-F-A | GEN276X162R197X296-6-F-A-GP | ZZ.SCREW.511 | GEN276X162R197X296-6-F-A | 334.65 | 2814.96 | 0 | NO |
| H10 | GEN276X162R197X296-6-F-A | GEN276X162R197X296-6-F-A-GP | ZZ.SCREW.511 | GEN276X162R197X296-6-F-A | 2755.91 | 2795.28 | 0 | NO |
| H11 | GEN276X162R197X296-6-F-A | GEN276X162R197X296-6-F-A-GP | ZZ.SCREW.511 | GEN276X162R197X296-6-F-A | 9980.31 | 1633.76 | 0 | NO |
| H12 | GEN276X162R197X296-6-F-A | GEN276X162R197X296-6-F-A-GP | ZZ.SCREW.511 | GEN276X162R197X296-6-F-A | 9980.31 | 19035.34 | 0 | NO |
| H13 | GEN276X162R197X296-6-F-A | GEN276X162R197X296-6-F-A-GP | ZZ.SCREW.511 | GEN276X162R197X296-6-F-A | 1338.58 | 177.17 | 0 | NO |
| J1 | SD-78827-0001 | PCISLT68-14-GP-U1 | 020.F0381.0068 | SD-78827-0001 | 8903.5400000000009 | 14829.53 | 90 | NO |
| J2 | SD-78827-0001 | PCISLT68-14-GP-U1 | 020.F0381.0068 | SD-78827-0001 | 8903.5400000000009 | 10774.41 | 90 | NO |
| J3 | SD-78827-0001 | PCISLT68-14-GP-U1 | 020.F0381.0068 | SD-78827-0001 | 8903.5400000000009 | 6719.29 | 90 | NO |
| J4 | SD-78827-0001 | PCISLT68-14-GP-U1 | 020.F0381.0068 | SD-78827-0001 | 8903.5400000000009 | 2664.17 | 90 | NO |
| J5 | SD-78827-0001 | PCISLT68-14-GP-U1 | 020.F0381.0068 | SD-78827-0001 | 1620.08 | 18884.650000000001 | 90 | NO |
| J6 | SD-78827-0001 | PCISLT68-14-GP-U1 | 020.F0381.0068 | SD-78827-0001 | 1620.08 | 14829.53 | 90 | NO |
| J7 | SD-78827-0001 | PCISLT68-14-GP-U1 | 020.F0381.0068 | SD-78827-0001 | 1620.08 | 10774.41 | 90 | NO |
| J8 | SD-78827-0001 | PCISLT68-14-GP-U1 | 020.F0381.0068 | SD-78827-0001 | 1620.08 | 6719.29 | 90 | NO |
| J9 | SD-78827-0001 | PCISLT68-14-GP-U1 | 020.F0381.0068 | SD-78827-0001 | 1620.08 | 2664.17 | 90 | NO |
| J10 | SD-78827-0001 | PCISLT68-14-GP-U1 | 020.F0381.0068 | SD-78827-0001 | 820.87 | 17257.09 | 270 | NO |
| J11 | SD-78827-0001 | PCISLT68-14-GP-U1 | 020.F0381.0068 | SD-78827-0001 | 820.87 | 13201.97 | 270 | NO |
| J12 | SD-78827-0001 | PCISLT68-14-GP-U1 | 020.F0381.0068 | SD-78827-0001 | 820.87 | 9146.85 | 270 | NO |
| J13 | SD-78827-0001 | PCISLT68-14-GP-U1 | 020.F0381.0068 | SD-78827-0001 | 820.87 | 5091.7299999999996 | 270 | NO |
| J14 | SD-78827-0001 | PCISLT68-14-GP-U1 | 020.F0381.0068 | SD-78827-0001 | 820.87 | 1036.6099999999999 | 270 | NO |
| J17 | G639F200221431HR-U | PCISLT200-5-GP-U | 020.50103.0200 | G639F200221431HR-U | 118.11 | 16737.87 | 90 | NO |
| J18 | G639F200221431HR-U | PCISLT200-5-GP-U | 020.50103.0200 | G639F200221431HR-U | 118.11 | 12564.65 | 90 | NO |
| J19 | G639F200221431HR-U | PCISLT200-5-GP-U | 020.50103.0200 | G639F200221431HR-U | 118.11 | 7604.02 | 90 | NO |
| J100 | SD-78827-0001 | PCISLT68-14-GP-U1 | 020.F0381.0068 | SD-78827-0001 | 8903.5400000000009 | 18884.650000000001 | 90 | NO |
| LED1 | LED1613-4PH20 | LED-RB-4-GP | 83.19226.C70 | LED1613-4PH20 | 8996.06 | 13783.46 | 0 | NO |
| LED2 | LED1613-4PH20 | LED-RB-4-GP | 83.19226.C70 | LED1613-4PH20 | 8996.06 | 9728.35 | 0 | NO |
| LED3 | LED1613-4PH20 | LED-RB-4-GP | 83.19226.C70 | LED1613-4PH20 | 8996.06 | 5673.23 | 0 | NO |
| LED4 | LED1613-4PH20 | LED-RB-4-GP | 83.19226.C70 | LED1613-4PH20 | 8996.06 | 1618.11 | 0 | NO |
| LED5 | LED1613-4PH20 | LED-RB-4-GP | 83.19226.C70 | LED1613-4PH20 | 1712.6 | 17838.580000000002 | 0 | NO |
| LED6 | LED1613-4PH20 | LED-RB-4-GP | 83.19226.C70 | LED1613-4PH20 | 1712.6 | 13783.46 | 0 | NO |
| LED7 | LED1613-4PH20 | LED-RB-4-GP | 83.19226.C70 | LED1613-4PH20 | 1712.6 | 9728.35 | 0 | NO |
| LED8 | LED1613-4PH20 | LED-RB-4-GP | 83.19226.C70 | LED1613-4PH20 | 1712.6 | 5673.23 | 0 | NO |
| LED9 | LED1613-4PH20 | LED-RB-4-GP | 83.19226.C70 | LED1613-4PH20 | 1712.6 | 1618.11 | 0 | NO |
| LED10 | LED1613-4PH20 | LED-RB-4-GP | 83.19226.C70 | LED1613-4PH20 | 728.35 | 18303.150000000001 | 0 | NO |
| LED11 | LED1613-4PH20 | LED-RB-4-GP | 83.19226.C70 | LED1613-4PH20 | 728.35 | 14248.03 | 0 | NO |
| LED12 | LED1613-4PH20 | LED-RB-4-GP | 83.19226.C70 | LED1613-4PH20 | 728.35 | 10192.91 | 0 | NO |
| LED13 | LED1613-4PH20 | LED-RB-4-GP | 83.19226.C70 | LED1613-4PH20 | 728.35 | 6137.8 | 0 | NO |
| LED14 | LED1613-4PH20 | LED-RB-4-GP | 83.19226.C70 | LED1613-4PH20 | 728.35 | 2082.6799999999998 | 0 | NO |
| LED100 | LED1613-4PH20 | LED-RB-4-GP | 83.19226.C70 | LED1613-4PH20 | 8996.06 | 17838.580000000002 | 0 | NO |
| PC1096 | C1206-TO0D3H75 | SC22U25V6KX-GP-U | 078.22622.082N | C1206-TO0D3H75 | 347 | 18652 | 90 | NO |
| PC1163 | C603H36 | SCD1U50V3KX-GP | 78.10424.2BL | C603H36 | 343 | 18321 | 90 | NO |
| PC1164 | C603H36 | SCD1U50V3KX-GP | 78.10424.2BL | C603H36 | 343 | 18273 | 90 | NO |
| PC1165 | C402H22 | SCD01U50V2KX-1GP | 78.10324.2FL | C402H22 | 344 | 18232 | 90 | NO |
| PC1166 | C1206-TO0D3H75 | SC22U25V6KX-GP-U | 078.22622.082N | C1206-TO0D3H75 | 347 | 18529 | 90 | NO |
| PC1167 | C1206-TO0D3H75 | SC22U25V6KX-GP-U | 078.22622.082N | C1206-TO0D3H75 | 347 | 18775 | 90 | NO |
| PC1168 | C1206-TO0D3H75 | SC22U25V6KX-GP-U | 078.22622.082N | C1206-TO0D3H75 | 347 | 18406 | 90 | NO |
| PC1169 | C402H22 | SCD01U50V2KX-1GP | 78.10324.2FL | C402H22 | 344 | 18197 | 90 | NO |
| PC1180 | C1206-TO0D3H75 | SC22U25V6KX-GP-U | 078.22622.082N | C1206-TO0D3H75 | 1070 | 16525 | 180 | NO |
| PC1181 | C1206-TO0D3H75 | SC22U25V6KX-GP-U | 078.22622.082N | C1206-TO0D3H75 | 1000 | 16329 | 0 | NO |
| PC1182 | C603H36 | SCD1U50V3KX-GP | 78.10424.2BL | C603H36 | 1086 | 16310 | 0 | NO |
| PC1183 | C402H22 | SCD01U50V2KX-1GP | 78.10324.2FL | C402H22 | 989 | 16543 | 180 | NO |
| PC1184 | C603H36 | SCD1U25V3KX-GP | 78.10422.2BL | C603H36 | 1000 | 17525 | 180 | NO |
| PC1185 | C1206-TO0D3H75 | SC22U25V6KX-GP-U | 078.22622.082N | C1206-TO0D3H75 | 8380 | 19625 | 180 | NO |
| PC1186 | C1206-TO0D3H75 | SC22U25V6KX-GP-U | 078.22622.082N | C1206-TO0D3H75 | 8255 | 19625 | 180 | NO |
| PC1187 | C603H36 | SCD1U50V3KX-GP | 78.10424.2BL | C603H36 | 8465 | 19645 | 180 | NO |
| PC1188 | C402H22 | SCD01U50V2KX-1GP | 78.10324.2FL | C402H22 | 8625 | 19533 | 0 | NO |
| PC1189 | C603H36 | SCD1U25V3KX-GP | 78.10422.2BL | C603H36 | 8715 | 18670 | 180 | NO |
| PC1190 | C1206-TO0D3H75 | SC22U25V6KX-GP-U | 078.22622.082N | C1206-TO0D3H75 | 8660 | 11710 | 180 | NO |
| PC1191 | C1206-TO0D3H75 | SC22U25V6KX-GP-U | 078.22622.082N | C1206-TO0D3H75 | 8662 | 11515 | 0 | NO |
| PC1192 | C603H36 | SCD1U50V3KX-GP | 78.10424.2BL | C603H36 | 8745 | 11720 | 180 | NO |
| PC1193 | C402H22 | SCD01U50V2KX-1GP | 78.10324.2FL | C402H22 | 8741 | 11495 | 0 | NO |
| PC1194 | C603H36 | SCD1U25V3KX-GP | 78.10422.2BL | C603H36 | 8725 | 10565 | 180 | NO |
| PC1195 | C1206-TO0D3H75 | SC22U25V6KX-GP-U | 078.22622.082N | C1206-TO0D3H75 | 1379 | 3596 | 180 | NO |
| PC1196 | C1206-TO0D3H75 | SC22U25V6KX-GP-U | 078.22622.082N | C1206-TO0D3H75 | 1378 | 3399 | 0 | NO |
| PC1197 | C603H36 | SCD1U50V3KX-GP | 78.10424.2BL | C603H36 | 1466 | 3603 | 180 | NO |
| PC1198 | C402H22 | SCD01U50V2KX-1GP | 78.10324.2FL | C402H22 | 1457 | 3384 | 0 | NO |
| PC1199 | C603H36 | SCD1U25V3KX-GP | 78.10422.2BL | C603H36 | 1440 | 2445 | 180 | NO |
| PC1200 | C1206-TO0D3H75 | SC22U25V6KX-GP-U | 078.22622.082N | C1206-TO0D3H75 | 8740 | 3600 | 180 | NO |
| PC1201 | C1206-TO0D3H75 | SC22U25V6KX-GP-U | 078.22622.082N | C1206-TO0D3H75 | 8663 | 3405 | 0 | NO |
| PC1202 | C603H36 | SCD1U50V3KX-GP | 78.10424.2BL | C603H36 | 8655 | 3600 | 180 | NO |
| PC1203 | C402H22 | SCD01U50V2KX-1GP | 78.10324.2FL | C402H22 | 8742 | 3385 | 0 | NO |
| PC1204 | C603H36 | SCD1U25V3KX-GP | 78.10422.2BL | C603H36 | 8725 | 2480 | 0 | NO |
| PC1205 | C1206-TO0D3H75 | SC22U25V6KX-GP-U | 078.22622.082N | C1206-TO0D3H75 | 1099 | 19627 | 180 | NO |
| PC1206 | C1206-TO0D3H75 | SC22U25V6KX-GP-U | 078.22622.082N | C1206-TO0D3H75 | 974 | 19627 | 180 | NO |
| PC1207 | C603H36 | SCD1U50V3KX-GP | 78.10424.2BL | C603H36 | 1185 | 19646 | 180 | NO |
| PC1208 | C402H22 | SCD01U50V2KX-1GP | 78.10324.2FL | C402H22 | 1332 | 19527 | 0 | NO |
| PC1209 | C603H36 | SCD1U25V3KX-GP | 78.10422.2BL | C603H36 | 1440 | 18670 | 180 | NO |
| PC1210 | C1206-TO0D3H75 | SC22U25V6KX-GP-U | 078.22622.082N | C1206-TO0D3H75 | 996 | 4165 | 0 | NO |
| PC1211 | C1206-TO0D3H75 | SC22U25V6KX-GP-U | 078.22622.082N | C1206-TO0D3H75 | 1063 | 4360 | 180 | NO |
| PC1212 | C603H36 | SCD1U50V3KX-GP | 78.10424.2BL | C603H36 | 1084 | 4148 | 0 | NO |
| PC1213 | C402H22 | SCD01U50V2KX-1GP | 78.10324.2FL | C402H22 | 984 | 4374 | 180 | NO |
| PC1214 | C603H36 | SCD1U25V3KX-GP | 78.10422.2BL | C603H36 | 1000 | 5280 | 180 | NO |
| PC1215 | C1206-TO0D3H75 | SC22U25V6KX-GP-U | 078.22622.082N | C1206-TO0D3H75 | 1379 | 7652 | 180 | NO |
| PC1216 | C1206-TO0D3H75 | SC22U25V6KX-GP-U | 078.22622.082N | C1206-TO0D3H75 | 1378 | 7456 | 0 | NO |
| PC1217 | C603H36 | SCD1U50V3KX-GP | 78.10424.2BL | C603H36 | 1465 | 7651 | 180 | NO |
| PC1218 | C402H22 | SCD01U50V2KX-1GP | 78.10324.2FL | C402H22 | 1458 | 7441 | 0 | NO |
| PC1219 | C603H36 | SCD1U25V3KX-GP | 78.10422.2BL | C603H36 | 1440 | 6510 | 180 | NO |
| PC1220 | C1206-TO0D3H75 | SC22U25V6KX-GP-U | 078.22622.082N | C1206-TO0D3H75 | 1064 | 12274 | 0 | NO |
| PC1221 | C1206-TO0D3H75 | SC22U25V6KX-GP-U | 078.22622.082N | C1206-TO0D3H75 | 1064 | 12468 | 180 | NO |
| PC1222 | C603H36 | SCD1U50V3KX-GP | 78.10424.2BL | C603H36 | 976 | 12264 | 0 | NO |
| PC1223 | C402H22 | SCD01U50V2KX-1GP | 78.10324.2FL | C402H22 | 984 | 12484 | 180 | NO |
| PC1224 | C603H36 | SCD1U25V3KX-GP | 78.10422.2BL | C603H36 | 1000 | 13380 | 180 | NO |
| PC1225 | C1206-TO0D3H75 | SC22U25V6KX-GP-U | 078.22622.082N | C1206-TO0D3H75 | 8740 | 7655 | 180 | NO |
| PC1226 | C1206-TO0D3H75 | SC22U25V6KX-GP-U | 078.22622.082N | C1206-TO0D3H75 | 8661 | 7458 | 0 | NO |
| PC1227 | C603H36 | SCD1U50V3KX-GP | 78.10424.2BL | C603H36 | 8650 | 7659 | 180 | NO |
| PC1228 | C402H22 | SCD01U50V2KX-1GP | 78.10324.2FL | C402H22 | 8741 | 7450 | 0 | NO |
| PC1229 | C603H36 | SCD1U25V3KX-GP | 78.10422.2BL | C603H36 | 8725 | 6510 | 180 | NO |
| PC1230 | C1206-TO0D3H75 | SC22U25V6KX-GP-U | 078.22622.082N | C1206-TO0D3H75 | 1396 | 538 | 180 | NO |
| PC1231 | C1206-TO0D3H75 | SC22U25V6KX-GP-U | 078.22622.082N | C1206-TO0D3H75 | 1521 | 538 | 180 | NO |
| PC1232 | C603H36 | SCD1U50V3KX-GP | 78.10424.2BL | C603H36 | 1310 | 538 | 180 | NO |
| PC1233 | C402H22 | SCD01U50V2KX-1GP | 78.10324.2FL | C402H22 | 1157 | 418 | 180 | NO |
| PC1234 | C603H36 | SCD1U25V3KX-GP | 78.10422.2BL | C603H36 | 1000 | 1220 | 180 | NO |
| PC1235 | C1206-TO0D3H75 | SC22U25V6KX-GP-U | 078.22622.082N | C1206-TO0D3H75 | 8745 | 15775 | 180 | NO |
| PC1236 | C1206-TO0D3H75 | SC22U25V6KX-GP-U | 078.22622.082N | C1206-TO0D3H75 | 8663 | 15577 | 0 | NO |
| PC1237 | C603H36 | SCD1U50V3KX-GP | 78.10424.2BL | C603H36 | 8660 | 15775 | 180 | NO |
| PC1238 | C402H22 | SCD01U50V2KX-1GP | 78.10324.2FL | C402H22 | 8742 | 15557 | 0 | NO |
| PC1239 | C603H36 | SCD1U25V3KX-GP | 78.10422.2BL | C603H36 | 8725 | 14620 | 180 | NO |
| PC1240 | C1206-TO0D3H75 | SC22U25V6KX-GP-U | 078.22622.082N | C1206-TO0D3H75 | 1455 | 15765 | 180 | NO |
| PC1241 | C1206-TO0D3H75 | SC22U25V6KX-GP-U | 078.22622.082N | C1206-TO0D3H75 | 1376 | 15563 | 0 | NO |
| PC1242 | C603H36 | SCD1U50V3KX-GP | 78.10424.2BL | C603H36 | 1367 | 15770 | 180 | NO |
| PC1243 | C402H22 | SCD01U50V2KX-1GP | 78.10324.2FL | C402H22 | 1458 | 15523 | 0 | NO |
| PC1244 | C603H36 | SCD1U25V3KX-GP | 78.10422.2BL | C603H36 | 1440 | 14610 | 180 | NO |
| PC1245 | C1206-TO0D3H75 | SC22U25V6KX-GP-U | 078.22622.082N | C1206-TO0D3H75 | 1400 | 11700 | 180 | NO |
| PC1246 | C1206-TO0D3H75 | SC22U25V6KX-GP-U | 078.22622.082N | C1206-TO0D3H75 | 1378 | 11506 | 0 | NO |
| PC1247 | C603H36 | SCD1U50V3KX-GP | 78.10424.2BL | C603H36 | 1485 | 11715 | 180 | NO |
| PC1248 | C402H22 | SCD01U50V2KX-1GP | 78.10324.2FL | C402H22 | 1458 | 11486 | 0 | NO |
| PC1249 | C603H36 | SCD1U25V3KX-GP | 78.10422.2BL | C603H36 | 1440 | 10565 | 180 | NO |
| PC1250 | C1206-TO0D3H75 | SC22U25V6KX-GP-U | 078.22622.082N | C1206-TO0D3H75 | 1002 | 8217 | 0 | NO |
| PC1251 | C1206-TO0D3H75 | SC22U25V6KX-GP-U | 078.22622.082N | C1206-TO0D3H75 | 1063 | 8411 | 180 | NO |
| PC1252 | C603H36 | SCD1U50V3KX-GP | 78.10424.2BL | C603H36 | 1087 | 8203 | 0 | NO |
| PC1253 | C402H22 | SCD01U50V2KX-1GP | 78.10324.2FL | C402H22 | 984 | 8429 | 180 | NO |
| PC1254 | C603H36 | SCD1U25V3KX-GP | 78.10422.2BL | C603H36 | 1000 | 9330 | 180 | NO |
| PC1259 | C402H22 | SCD1U25V2KX-2-GP | 78.10422.2FL | C402H22 | 8875 | 16980 | 270 | NO |
| PC1263 | C603H36 | SC1U16V3KX-5GP | 78.10521.2BL | C603H36 | 9105 | 17105 | 180 | NO |
| PC1272 | C805H56 | SC22U6D3V5MX-5-GP | 78.22610.81L | C805H56 | 8355 | 17310 | 180 | NO |
| PC1273 | C603H36 | SCD1U50V3KX-GP | 78.10424.2BL | C603H36 | 8550 | 16995 | 180 | NO |
| PC1274 | C603H36 | SCD1U50V3KX-GP | 78.10424.2BL | C603H36 | 8770 | 16980 | 0 | NO |
| PC1275 | C402-TO0D2H28 | SC2D2U16V2KX-GP | 078.22521.05F1 | C402-TO0D2H28 | 8945 | 17290 | 180 | NO |
| PC1276 | C1206-TO0D3H75 | SC22U25V6KX-GP-U | 078.22622.082N | C1206-TO0D3H75 | 8843.43 | 16710.37 | 270 | NO |
| PC1279 | C402H22 | SC3300P50V2KX-1GP | 78.33224.2FL | C402H22 | 9165 | 17190 | 90 | NO |
| PC1280 | C402H22 | SCD1U16V2KX-3GP | 78.10421.2FL | C402H22 | 8415 | 17005 | 0 | NO |
| PC1281 | C603H36 | SC1U25V3KX-GP | 78.10522.2BL | C603H36 | 8965 | 16880 | 0 | NO |
| PC1282 | C805H62 | SC47U10V5MX-GP-U | 078.47613.0511 | C805H62 | 8275 | 17310 | 180 | NO |
| PC1283 | C402H22 | SC1KP50V2KX-1GP | 78.10224.2FL | C402H22 | 9135 | 16910 | 270 | NO |
| PC1284 | C1206-TO0D3H75 | SC22U25V6KX-GP-U | 078.22622.082N | C1206-TO0D3H75 | 8843.43 | 16835 | 270 | NO |
| PC1285 | C805H62 | SC47U10V5MX-GP-U | 078.47613.0511 | C805H62 | 8275 | 17040 | 0 | NO |
| PC1286 | C805H56 | SC22U6D3V5MX-5-GP | 78.22610.81L | C805H56 | 8355 | 17040 | 0 | NO |
| PC1287 | C603 | SC2K2P50V3KX-GP | 78.22224.2BL | C603 | 8780 | 17260 | 180 | NO |
| PC1288 | C402H22 | SC1U10V2KX-7-GP | 078.10523.08FV | C402H22 | 9135 | 16990 | 270 | NO |
| PC1289 | C603H36 | SCD1U25V3KX-GP | 78.10422.2BL | C603H36 | 9590 | 16244 | 0 | NO |
| PC1290 | C1206H71 | SC10U25V6KX-4GP | 78.10622.22L | C1206H71 | 9838 | 14198 | 0 | NO |
| PC1291 | C603H36 | SCD1U25V3KX-GP | 78.10422.2BL | C603H36 | 9905 | 14195 | 0 | NO |
| PG3 | CON2C-U | COPPER-CLOSE-GP-U | ZZ.CON2C.XXX | CON2C-U | 9165 | 17245 | 180 | NO |
| PG4 | GAP-CLOSE-PWR-4 | GAP-CLOSE-PWR-4-GP | ZZ.C0N2C.011 | GAP-CLOSE-PWR-4 | 8225 | 17300 | 90 | NO |
| PL2 | L7066-1830-UH119 | COIL-6D8UH-10-GP | 68.6R810.20P | L7066-1830-UH119 | 8575 | 17200 | 270 | NO |
| PR96 | R402H16 | 37K4R2F-1-GP | 64.37425.6DL | R402H16 | 8985 | 17290 | 0 | NO |
| PR97 | R402H16 | 10KR2F-2-GP | 64.10025.6DL | R402H16 | 8905 | 17290 | 180 | NO |
| PR9008 | R402H16 | 4K7R2F-GP | 64.47015.6DL | R402H16 | 3325 | 16770 | 90 | NO |
| PR9009 | R402H16 | 4K7R2F-GP | 64.47015.6DL | R402H16 | 3365 | 16910 | 90 | NO |
| PR9038 | R402H16 | 4K7R2F-GP | 64.47015.6DL | R402H16 | 3365 | 11905 | 90 | NO |
| PR9039 | R402H16 | 4K7R2F-GP | 64.47015.6DL | R402H16 | 3325 | 8070 | 90 | NO |
| PR9040 | R402H16 | 4K7R2F-GP | 64.47015.6DL | R402H16 | 3365 | 8230 | 270 | NO |
| PR9041 | R402H16 | 4K7R2F-GP | 64.47015.6DL | R402H16 | 3325 | 3770 | 90 | NO |
| PR9042 | R402H16 | 4K7R2F-GP | 64.47015.6DL | R402H16 | 3365 | 3930 | 270 | NO |
| PR9047 | R402H16 | 0R2J-2-GP | 63.R0034.1DL | R402H16 | 3195 | 13940 | 180 | NO |
| PR9048 | R402H16 | 0R2J-2-GP | 63.R0034.1DL | R402H16 | 3275 | 6050 | 270 | NO |
| PR9057 | R402H16 | 0R2J-2-GP | 63.R0034.1DL | R402H16 | 2765 | 17160 | 180 | NO |
| PR9058 | R402H16 | 0R2J-2-GP | 63.R0034.1DL | R402H16 | 2725 | 17160 | 180 | NO |
| PR9059 | R402H16 | 0R2J-2-GP | 63.R0034.1DL | R402H16 | 3275 | 6090 | 90 | NO |
| PR9060 | R402H16 | 0R2J-2-GP | 63.R0034.1DL | R402H16 | 9530 | 16685 | 90 | NO |
| PR9061 | R402H16 | 1K4R2F-1-GP | 64.14015.6DL | R402H16 | 3265 | 17130 | 270 | NO |
| PR9062 | R402H16 | 1K4R2F-1-GP | 64.14015.6DL | R402H16 | 3265 | 12145 | 270 | NO |
| PR9063 | R402H16 | 1K4R2F-1-GP | 64.14015.6DL | R402H16 | 3265 | 8430 | 270 | NO |
| PR9064 | R402H16 | 1K4R2F-1-GP | 64.14015.6DL | R402H16 | 3265 | 4130 | 270 | NO |
| PR9065 | R402H16 | 0R2J-2-GP | 63.R0034.1DL | R402H16 | 9530 | 16635 | 90 | NO |
| PR9077 | R402H16 | 10KR2F-2-GP | 64.10025.6DL | R402H16 | 9135 | 17030 | 270 | NO |
| PR9079 | R402H16 | 10KR2F-2-GP | 64.10025.6DL | R402H16 | 9175 | 17150 | 90 | NO |
| PR9080 | R402H16 | 0R2J-2-GP | 63.R0034.1DL | R402H16 | 8815 | 16980 | 180 | NO |
| PR9081 | R402H16 | 0R2J-2-GP | 63.R0034.1DL | R402H16 | 9060 | 16895 | 0 | NO |
| PR9083 | R603H22 | 2D2R3-1-U-GP | 64.2R205.55L | R603H22 | 9015 | 16880 | 0 | NO |
| PR9084 | R402H16 | 2KR2F-3-GP | 64.20015.6DL | R402H16 | 8595 | 17010 | 0 | NO |
| PR9085 | R603H22 | 10R3F-GP | 64.10R05.55L | R603H22 | 9225 | 16950 | 270 | NO |
| PR9086 | R1206H28 | 0R6J-3-GP | 63.R0032.11L | R1206H28 | 8843.5300000000007 | 16602.490000000002 | 270 | NO |
| PR9087 | R1206H28 | 0R6J-3-GP | 63.R0032.11L | R1206H28 | 8145 | 17235 | 90 | NO |
| PR9088 | R1206H28 | 0R6J-3-GP | 63.R0032.11L | R1206H28 | 8145 | 17145 | 90 | NO |
| PR9090 | R402H16 | 33KR2F-2-GP | 64.33025.L0L | R402H16 | 9135 | 16950 | 270 | NO |
| PR9091 | R805H24 | 3D01R5F-GP | 64.3R015.16L | R805H24 | 8845 | 17270 | 0 | NO |
| PU2 | QFN16G3-G1D7H40 | TPS53312RGTR-GP | 74.53312.073 | QFN16G3-G1D7H40 | 8935 | 17100 | 270 | NO |
| Q8 | SOT23DGS2D4H48 | 2N7002A-7-GP | 84.2N702.E31 | SOT23DGS2D4H48 | 7888.39 | 19495.07 | 180 | NO |
| Q9 | SOT23DGS2D4H48 | 2N7002A-7-GP | 84.2N702.E31 | SOT23DGS2D4H48 | 8240 | 15755 | 180 | NO |
| Q10 | SOT23DGS2D4H48 | 2N7002A-7-GP | 84.2N702.E31 | SOT23DGS2D4H48 | 8240 | 11700 | 180 | NO |
| Q11 | SOT23DGS2D4H48 | 2N7002A-7-GP | 84.2N702.E31 | SOT23DGS2D4H48 | 8240 | 7645 | 180 | NO |
| Q12 | SOT23DGS2D4H48 | 2N7002A-7-GP | 84.2N702.E31 | SOT23DGS2D4H48 | 8240 | 3590 | 180 | NO |
| Q13 | SOT23DGS2D4H48 | 2N7002A-7-GP | 84.2N702.E31 | SOT23DGS2D4H48 | 655 | 19505 | 180 | NO |
| Q14 | SOT23DGS2D4H48 | 2N7002A-7-GP | 84.2N702.E31 | SOT23DGS2D4H48 | 950 | 15665 | 180 | NO |
| Q15 | SOT23DGS2D4H48 | 2N7002A-7-GP | 84.2N702.E31 | SOT23DGS2D4H48 | 957 | 11704 | 180 | NO |
| Q16 | SOT23DGS2D4H48 | 2N7002A-7-GP | 84.2N702.E31 | SOT23DGS2D4H48 | 957 | 7645 | 180 | NO |
| Q17 | SOT23DGS2D4H48 | 2N7002A-7-GP | 84.2N702.E31 | SOT23DGS2D4H48 | 957 | 3590 | 180 | NO |
| Q18 | SOT23DGS2D4H48 | 2N7002A-7-GP | 84.2N702.E31 | SOT23DGS2D4H48 | 1499 | 16331 | 0 | NO |
| Q19 | SOT23DGS2D4H48 | 2N7002A-7-GP | 84.2N702.E31 | SOT23DGS2D4H48 | 1487 | 12276 | 0 | NO |
| Q20 | SOT23DGS2D4H48 | 2N7002A-7-GP | 84.2N702.E31 | SOT23DGS2D4H48 | 1484 | 8221 | 0 | NO |
| Q21 | SOT23DGS2D4H48 | 2N7002A-7-GP | 84.2N702.E31 | SOT23DGS2D4H48 | 1484 | 4166 | 0 | NO |
| Q22 | SOT23DGS2D4H48 | 2N7002A-7-GP | 84.2N702.E31 | SOT23DGS2D4H48 | 1970 | 425 | 0 | NO |
| Q23 | SOT23DGS2D4H48 | 2N7002A-7-GP | 84.2N702.E31 | SOT23DGS2D4H48 | 7787.39 | 19644.07 | 270 | NO |
| Q24 | SOT23DGS2D4H48 | 2N7002A-7-GP | 84.2N702.E31 | SOT23DGS2D4H48 | 7982.39 | 19644.07 | 270 | NO |
| Q28 | SOT23DGS2D4H48 | 2N7002A-7-GP | 84.2N702.E31 | SOT23DGS2D4H48 | 8690 | 17600 | 0 | NO |
| Q29 | SOT23DGS2D4H48 | 2N7002A-7-GP | 84.2N702.E31 | SOT23DGS2D4H48 | 9205 | 17630 | 180 | NO |
| Q30 | SOT23DGS2D4H48 | 2N7002A-7-GP | 84.2N702.E31 | SOT23DGS2D4H48 | 8745 | 17760 | 0 | NO |
| Q31 | SOT23DGS2D4H48 | 2N7002A-7-GP | 84.2N702.E31 | SOT23DGS2D4H48 | 8305 | 15904 | 270 | NO |
| Q32 | SOT23DGS2D4H48 | 2N7002A-7-GP | 84.2N702.E31 | SOT23DGS2D4H48 | 8500 | 15904 | 270 | NO |
| Q33 | SOT23DGS2D4H48 | 2N7002A-7-GP | 84.2N702.E31 | SOT23DGS2D4H48 | 9205 | 13574.88 | 180 | NO |
| Q34 | SOT23DGS2D4H48 | 2N7002A-7-GP | 84.2N702.E31 | SOT23DGS2D4H48 | 8690 | 13544.88 | 0 | NO |
| Q35 | SOT23DGS2D4H48 | 2N7002A-7-GP | 84.2N702.E31 | SOT23DGS2D4H48 | 8745 | 13704.88 | 0 | NO |
| Q36 | SOT23DGS2D4H48 | 2N7002A-7-GP | 84.2N702.E31 | SOT23DGS2D4H48 | 8305 | 11849 | 270 | NO |
| Q37 | SOT23DGS2D4H48 | 2N7002A-7-GP | 84.2N702.E31 | SOT23DGS2D4H48 | 8500 | 11849 | 270 | NO |
| Q38 | SOT23DGS2D4H48 | 2N7002A-7-GP | 84.2N702.E31 | SOT23DGS2D4H48 | 9205 | 9519.77 | 180 | NO |
| Q39 | SOT23DGS2D4H48 | 2N7002A-7-GP | 84.2N702.E31 | SOT23DGS2D4H48 | 8690 | 9489.77 | 0 | NO |
| Q40 | SOT23DGS2D4H48 | 2N7002A-7-GP | 84.2N702.E31 | SOT23DGS2D4H48 | 8745 | 9649.77 | 0 | NO |
| Q41 | SOT23DGS2D4H48 | 2N7002A-7-GP | 84.2N702.E31 | SOT23DGS2D4H48 | 8500 | 7794 | 270 | NO |
| Q42 | SOT23DGS2D4H48 | 2N7002A-7-GP | 84.2N702.E31 | SOT23DGS2D4H48 | 8305 | 7794 | 270 | NO |
| Q43 | SOT23DGS2D4H48 | 2N7002A-7-GP | 84.2N702.E31 | SOT23DGS2D4H48 | 9205 | 5464.65 | 180 | NO |
| Q44 | SOT23DGS2D4H48 | 2N7002A-7-GP | 84.2N702.E31 | SOT23DGS2D4H48 | 8690 | 5434.65 | 0 | NO |
| Q45 | SOT23DGS2D4H48 | 2N7002A-7-GP | 84.2N702.E31 | SOT23DGS2D4H48 | 8745 | 5594.65 | 0 | NO |
| Q46 | SOT23DGS2D4H48 | 2N7002A-7-GP | 84.2N702.E31 | SOT23DGS2D4H48 | 8500 | 3739 | 270 | NO |
| Q47 | SOT23DGS2D4H48 | 2N7002A-7-GP | 84.2N702.E31 | SOT23DGS2D4H48 | 8305 | 3739 | 270 | NO |
| Q48 | SOT23DGS2D4H48 | 2N7002A-7-GP | 84.2N702.E31 | SOT23DGS2D4H48 | 9205 | 1409.53 | 180 | NO |
| Q49 | SOT23DGS2D4H48 | 2N7002A-7-GP | 84.2N702.E31 | SOT23DGS2D4H48 | 8730 | 1450 | 270 | NO |
| Q50 | SOT23DGS2D4H48 | 2N7002A-7-GP | 84.2N702.E31 | SOT23DGS2D4H48 | 8761.61 | 1596.61 | 0 | NO |
| Q51 | SOT23DGS2D4H48 | 2N7002A-7-GP | 84.2N702.E31 | SOT23DGS2D4H48 | 707 | 19652 | 270 | NO |
| Q52 | SOT23DGS2D4H48 | 2N7002A-7-GP | 84.2N702.E31 | SOT23DGS2D4H48 | 516 | 19653 | 270 | NO |
| Q53 | SOT23DGS2D4H48 | 2N7002A-7-GP | 84.2N702.E31 | SOT23DGS2D4H48 | 1843.46 | 17635 | 90 | NO |
| Q54 | SOT23DGS2D4H48 | 2N7002A-7-GP | 84.2N702.E31 | SOT23DGS2D4H48 | 2210 | 17600 | 180 | NO |
| Q55 | SOT23DGS2D4H48 | 2N7002A-7-GP | 84.2N702.E31 | SOT23DGS2D4H48 | 2355 | 17600 | 180 | NO |
| Q56 | SOT23DGS2D4H48 | 2N7002A-7-GP | 84.2N702.E31 | SOT23DGS2D4H48 | 1128.75 | 15847.75 | 270 | NO |
| Q57 | SOT23DGS2D4H48 | 2N7002A-7-GP | 84.2N702.E31 | SOT23DGS2D4H48 | 933.75 | 15847.75 | 270 | NO |
| Q58 | SOT23DGS2D4H48 | 2N7002A-7-GP | 84.2N702.E31 | SOT23DGS2D4H48 | 1921.54 | 13574.88 | 180 | NO |
| Q59 | SOT23DGS2D4H48 | 2N7002A-7-GP | 84.2N702.E31 | SOT23DGS2D4H48 | 1550 | 13680.35 | 180 | NO |
| Q60 | SOT23DGS2D4H48 | 2N7002A-7-GP | 84.2N702.E31 | SOT23DGS2D4H48 | 1405 | 13680.35 | 0 | NO |
| Q61 | SOT23DGS2D4H48 | 2N7002A-7-GP | 84.2N702.E31 | SOT23DGS2D4H48 | 1235 | 11849 | 270 | NO |
| Q62 | SOT23DGS2D4H48 | 2N7002A-7-GP | 84.2N702.E31 | SOT23DGS2D4H48 | 1040 | 11849 | 270 | NO |
| Q63 | SOT23DGS2D4H48 | 2N7002A-7-GP | 84.2N702.E31 | SOT23DGS2D4H48 | 1515 | 9675 | 0 | NO |
| Q64 | SOT23DGS2D4H48 | 2N7002A-7-GP | 84.2N702.E31 | SOT23DGS2D4H48 | 2050 | 9489.77 | 180 | NO |
| Q65 | SOT23DGS2D4H48 | 2N7002A-7-GP | 84.2N702.E31 | SOT23DGS2D4H48 | 2195 | 9489.77 | 180 | NO |
| Q66 | SOT23DGS2D4H48 | 2N7002A-7-GP | 84.2N702.E31 | SOT23DGS2D4H48 | 1040 | 7794 | 270 | NO |
| Q67 | SOT23DGS2D4H48 | 2N7002A-7-GP | 84.2N702.E31 | SOT23DGS2D4H48 | 1235 | 7794 | 270 | NO |
| Q68 | SOT23DGS2D4H48 | 2N7002A-7-GP | 84.2N702.E31 | SOT23DGS2D4H48 | 2060 | 5590 | 90 | NO |
| Q69 | SOT23DGS2D4H48 | 2N7002A-7-GP | 84.2N702.E31 | SOT23DGS2D4H48 | 1400 | 5600 | 180 | NO |
| Q70 | SOT23DGS2D4H48 | 2N7002A-7-GP | 84.2N702.E31 | SOT23DGS2D4H48 | 1255 | 5600 | 0 | NO |
| Q71 | SOT23DGS2D4H48 | 2N7002A-7-GP | 84.2N702.E31 | SOT23DGS2D4H48 | 1040 | 3739 | 270 | NO |
| Q72 | SOT23DGS2D4H48 | 2N7002A-7-GP | 84.2N702.E31 | SOT23DGS2D4H48 | 1235 | 3739 | 270 | NO |
| Q73 | SOT23DGS2D4H48 | 2N7002A-7-GP | 84.2N702.E31 | SOT23DGS2D4H48 | 1915 | 1445 | 180 | NO |
| Q74 | SOT23DGS2D4H48 | 2N7002A-7-GP | 84.2N702.E31 | SOT23DGS2D4H48 | 1510 | 1525 | 180 | NO |
| Q75 | SOT23DGS2D4H48 | 2N7002A-7-GP | 84.2N702.E31 | SOT23DGS2D4H48 | 1365 | 1525 | 0 | NO |
| Q76 | SOT23DGS2D4H48 | 2N7002A-7-GP | 84.2N702.E31 | SOT23DGS2D4H48 | 1400 | 16181 | 90 | NO |
| Q77 | SOT23DGS2D4H48 | 2N7002A-7-GP | 84.2N702.E31 | SOT23DGS2D4H48 | 1205 | 16181 | 90 | NO |
| Q78 | SOT23DGS2D4H48 | 2N7002A-7-GP | 84.2N702.E31 | SOT23DGS2D4H48 | 1013 | 18569 | 0 | NO |
| Q79 | SOT23DGS2D4H48 | 2N7002A-7-GP | 84.2N702.E31 | SOT23DGS2D4H48 | 731 | 18634 | 0 | NO |
| Q80 | SOT23DGS2D4H48 | 2N7002A-7-GP | 84.2N702.E31 | SOT23DGS2D4H48 | 676 | 18484 | 180 | NO |
| Q81 | SOT23DGS2D4H48 | 2N7002A-7-GP | 84.2N702.E31 | SOT23DGS2D4H48 | 1205 | 12126 | 90 | NO |
| Q82 | SOT23DGS2D4H48 | 2N7002A-7-GP | 84.2N702.E31 | SOT23DGS2D4H48 | 1400 | 12126 | 90 | NO |
| Q83 | SOT23DGS2D4H48 | 2N7002A-7-GP | 84.2N702.E31 | SOT23DGS2D4H48 | 635 | 14580 | 0 | NO |
| Q84 | SOT23DGS2D4H48 | 2N7002A-7-GP | 84.2N702.E31 | SOT23DGS2D4H48 | 980 | 14405 | 90 | NO |
| Q85 | SOT23DGS2D4H48 | 2N7002A-7-GP | 84.2N702.E31 | SOT23DGS2D4H48 | 769.58 | 14370.19 | 90 | NO |
| Q86 | SOT23DGS2D4H48 | 2N7002A-7-GP | 84.2N702.E31 | SOT23DGS2D4H48 | 1205 | 8071 | 90 | NO |
| Q87 | SOT23DGS2D4H48 | 2N7002A-7-GP | 84.2N702.E31 | SOT23DGS2D4H48 | 1400 | 8071 | 90 | NO |
| Q88 | SOT23DGS2D4H48 | 2N7002A-7-GP | 84.2N702.E31 | SOT23DGS2D4H48 | 670 | 10545 | 0 | NO |
| Q89 | SOT23DGS2D4H48 | 2N7002A-7-GP | 84.2N702.E31 | SOT23DGS2D4H48 | 980 | 10349.879999999999 | 90 | NO |
| Q90 | SOT23DGS2D4H48 | 2N7002A-7-GP | 84.2N702.E31 | SOT23DGS2D4H48 | 769.58 | 10315.07 | 90 | NO |
| Q91 | SOT23DGS2D4H48 | 2N7002A-7-GP | 84.2N702.E31 | SOT23DGS2D4H48 | 1201.25 | 4012.25 | 90 | NO |
| Q92 | SOT23DGS2D4H48 | 2N7002A-7-GP | 84.2N702.E31 | SOT23DGS2D4H48 | 1396.25 | 4012.25 | 90 | NO |
| Q93 | SOT23DGS2D4H48 | 2N7002A-7-GP | 84.2N702.E31 | SOT23DGS2D4H48 | 635 | 6469.77 | 0 | NO |
| Q94 | SOT23DGS2D4H48 | 2N7002A-7-GP | 84.2N702.E31 | SOT23DGS2D4H48 | 980 | 6294.77 | 90 | NO |
| Q95 | SOT23DGS2D4H48 | 2N7002A-7-GP | 84.2N702.E31 | SOT23DGS2D4H48 | 769.58 | 6259.96 | 90 | NO |
| Q96 | SOT23DGS2D4H48 | 2N7002A-7-GP | 84.2N702.E31 | SOT23DGS2D4H48 | 1710 | 276 | 90 | NO |
| Q97 | SOT23DGS2D4H48 | 2N7002A-7-GP | 84.2N702.E31 | SOT23DGS2D4H48 | 1905 | 276 | 90 | NO |
| Q98 | SOT23DGS2D4H48 | 2N7002A-7-GP | 84.2N702.E31 | SOT23DGS2D4H48 | 635 | 2414.65 | 0 | NO |
| Q99 | SOT23DGS2D4H48 | 2N7002A-7-GP | 84.2N702.E31 | SOT23DGS2D4H48 | 980 | 2239.65 | 90 | NO |
| Q100 | SOT23DGS2D4H48 | 2N7002A-7-GP | 84.2N702.E31 | SOT23DGS2D4H48 | 769.58 | 2204.84 | 90 | NO |
| R111 | R402H16 | 330R2F-GP | 64.33005.6DL | R402H16 | 9215 | 17865 | 270 | NO |
| R115 | R402H14 | 100R2J-2-GP | 63.10134.1DL | R402H14 | 954.87 | 18259.150000000001 | 270 | NO |
| R117 | R402H16 | 330R2F-GP | 64.33005.6DL | R402H16 | 955 | 18300 | 270 | NO |
| R118 | R402H16 | 4K7R2J-2-GP | 63.47234.1DL | R402H16 | 4290 | 17120 | 0 | NO |
| R119 | R402H16 | 4K7R2J-2-GP | 63.47234.1DL | R402H16 | 4290 | 17200 | 0 | NO |
| R120 | R402H14 | 100R2J-2-GP | 63.10134.1DL | R402H14 | 9215 | 17820 | 270 | NO |
| R123 | R402H16 | 4K7R2J-2-GP | 63.47234.1DL | R402H16 | 3465 | 16410 | 270 | NO |
| R124 | R402H16 | 4K7R2J-2-GP | 63.47234.1DL | R402H16 | 3545 | 16410 | 270 | NO |
| R137 | R402H16 | 4K7R2J-2-GP | 63.47234.1DL | R402H16 | 7908.39 | 19395.07 | 270 | NO |
| R138 | R402H16 | 4K7R2J-2-GP | 63.47234.1DL | R402H16 | 8260 | 15655 | 270 | NO |
| R139 | R402H16 | 4K7R2J-2-GP | 63.47234.1DL | R402H16 | 8260 | 11600 | 270 | NO |
| R141 | R402H16 | 4K7R2J-2-GP | 63.47234.1DL | R402H16 | 8260 | 7545 | 270 | NO |
| R142 | R402H16 | 4K7R2J-2-GP | 63.47234.1DL | R402H16 | 8260 | 3490 | 270 | NO |
| R143 | R402H16 | 4K7R2J-2-GP | 63.47234.1DL | R402H16 | 675 | 19405 | 270 | NO |
| R144 | R402H16 | 4K7R2J-2-GP | 63.47234.1DL | R402H16 | 970 | 15565 | 270 | NO |
| R145 | R402H16 | 4K7R2J-2-GP | 63.47234.1DL | R402H16 | 977 | 11604 | 270 | NO |
| R146 | R402H16 | 4K7R2J-2-GP | 63.47234.1DL | R402H16 | 977 | 7545 | 270 | NO |
| R147 | R402H16 | 4K7R2J-2-GP | 63.47234.1DL | R402H16 | 977 | 3490 | 270 | NO |
| R148 | R402H16 | 4K7R2J-2-GP | 63.47234.1DL | R402H16 | 1479 | 16431 | 90 | NO |
| R149 | R402H16 | 4K7R2J-2-GP | 63.47234.1DL | R402H16 | 1467 | 12376 | 90 | NO |
| R150 | R402H16 | 4K7R2J-2-GP | 63.47234.1DL | R402H16 | 1464 | 8321 | 90 | NO |
| R151 | R402H16 | 4K7R2J-2-GP | 63.47234.1DL | R402H16 | 1464 | 4266 | 90 | NO |
| R152 | R402H16 | 4K7R2J-2-GP | 63.47234.1DL | R402H16 | 1950 | 525 | 90 | NO |
| R314 | R402H16 | 0R2J-2-GP | 63.R0034.1DL | R402H16 | 8010 | 18120 | 90 | NO |
| R315 | R402H16 | 4K7R2F-GP | 64.47015.6DL | R402H16 | 8415 | 17900 | 180 | NO |
| R316 | R402H16 | 4K7R2F-GP | 64.47015.6DL | R402H16 | 8255 | 17900 | 180 | NO |
| R317 | R402H16 | 4K7R2J-2-GP | 63.47234.1DL | R402H16 | 8150 | 17900 | 180 | NO |
| R318 | R402H16 | 4K7R2F-GP | 64.47015.6DL | R402H16 | 2030 | 5370 | 0 | NO |
| R319 | R402H16 | 0R2J-2-GP | 63.R0034.1DL | R402H16 | 8010 | 18070 | 90 | NO |
| R320 | R402H16 | 0R2J-2-GP | 63.R0034.1DL | R402H16 | 1835 | 5310 | 270 | NO |
| R321 | R402H16 | 0R2J-2-GP | 63.R0034.1DL | R402H16 | 1835 | 5270 | 270 | NO |
| R322 | R402H16 | 4K7R2J-2-GP | 63.47234.1DL | R402H16 | 2030 | 5445 | 0 | NO |
| R323 | R402H16 | 4K7R2J-2-GP | 63.47234.1DL | R402H16 | 8375 | 17900 | 0 | NO |
| R324 | R402H16 | 4K7R2F-GP | 64.47015.6DL | R402H16 | 8295 | 17900 | 0 | NO |
| R325 | R402H16 | 4K7R2J-2-GP | 63.47234.1DL | R402H16 | 8190 | 17900 | 0 | NO |
| R326 | R402H16 | 0R2J-2-GP | 63.R0034.1DL | R402H16 | 8010 | 1980 | 90 | NO |
| R327 | R402H16 | 4K7R2F-GP | 64.47015.6DL | R402H16 | 8165 | 1760 | 180 | NO |
| R328 | R402H16 | 4K7R2F-GP | 64.47015.6DL | R402H16 | 8325 | 1760 | 180 | NO |
| R329 | R402H16 | 4K7R2J-2-GP | 63.47234.1DL | R402H16 | 8245 | 1760 | 180 | NO |
| R330 | R402H16 | 0R2J-2-GP | 63.R0034.1DL | R402H16 | 945 | 14970 | 90 | NO |
| R331 | R402H16 | 4K7R2F-GP | 64.47015.6DL | R402H16 | 1260 | 14750 | 180 | NO |
| R332 | R402H16 | 4K7R2J-2-GP | 63.47234.1DL | R402H16 | 1180 | 14750 | 180 | NO |
| R333 | R402H16 | 4K7R2J-2-GP | 63.47234.1DL | R402H16 | 1100 | 14750 | 180 | NO |
| R334 | R402H16 | 0R2J-2-GP | 63.R0034.1DL | R402H16 | 8010 | 1930 | 90 | NO |
| R335 | R402H16 | 0R2J-2-GP | 63.R0034.1DL | R402H16 | 945 | 14920 | 90 | NO |
| R336 | R402H16 | 4K7R2J-2-GP | 63.47234.1DL | R402H16 | 8365 | 1760 | 0 | NO |
| R337 | R402H16 | 4K7R2F-GP | 64.47015.6DL | R402H16 | 8285 | 1760 | 0 | NO |
| R338 | R402H16 | 4K7R2J-2-GP | 63.47234.1DL | R402H16 | 8205 | 1760 | 0 | NO |
| R339 | R402H16 | 4K7R2J-2-GP | 63.47234.1DL | R402H16 | 1300 | 14750 | 0 | NO |
| R340 | R402H16 | 4K7R2F-GP | 64.47015.6DL | R402H16 | 1220 | 14750 | 0 | NO |
| R341 | R402H16 | 4K7R2F-GP | 64.47015.6DL | R402H16 | 1140 | 14750 | 0 | NO |
| R342 | R402H16 | 4K7R2F-GP | 64.47015.6DL | R402H16 | 1990 | 5370 | 180 | NO |
| R343 | R402H16 | 4K7R2J-2-GP | 63.47234.1DL | R402H16 | 1990 | 5295 | 180 | NO |
| R344 | R402H16 | 4K7R2J-2-GP | 63.47234.1DL | R402H16 | 1990 | 5445 | 180 | NO |
| R345 | R402H16 | 4K7R2J-2-GP | 63.47234.1DL | R402H16 | 2915 | 17900 | 0 | NO |
| R346 | R402H16 | 4K7R2F-GP | 64.47015.6DL | R402H16 | 2835 | 17900 | 0 | NO |
| R347 | R402H16 | 4K7R2F-GP | 64.47015.6DL | R402H16 | 2755 | 17900 | 0 | NO |
| R348 | R402H16 | 4K7R2F-GP | 64.47015.6DL | R402H16 | 2875 | 17900 | 180 | NO |
| R349 | R402H16 | 4K7R2J-2-GP | 63.47234.1DL | R402H16 | 2795 | 17900 | 180 | NO |
| R350 | R402H16 | 4K7R2J-2-GP | 63.47234.1DL | R402H16 | 2715 | 17900 | 180 | NO |
| R351 | R402H16 | 0R2J-2-GP | 63.R0034.1DL | R402H16 | 2805 | 17330 | 0 | NO |
| R352 | R402H16 | 0R2J-2-GP | 63.R0034.1DL | R402H16 | 2765 | 17330 | 0 | NO |
| R353 | R402H16 | 4K7R2F-GP | 64.47015.6DL | R402H16 | 2030 | 5295 | 0 | NO |
| R354 | R402H16 | 0R2J-2-GP | 63.R0034.1DL | R402H16 | 2725 | 17330 | 0 | NO |
| R362 | R402H16 | 4K7R2F-GP | 64.47015.6DL | R402H16 | 3580 | 690 | 180 | NO |
| R364 | R402H16 | 4K7R2F-GP | 64.47015.6DL | R402H16 | 3485 | 735 | 180 | NO |
| R367 | R402H16 | 4K7R2J-2-GP | 63.47234.1DL | R402H16 | 2785 | 17220 | 270 | NO |
| R368 | R402H16 | 4K7R2J-2-GP | 63.47234.1DL | R402H16 | 2705 | 17220 | 90 | NO |
| R369 | R402H16 | 4K7R2J-2-GP | 63.47234.1DL | R402H16 | 9590 | 16700 | 0 | NO |
| R370 | R402H16 | 4K7R2J-2-GP | 63.47234.1DL | R402H16 | 9590 | 16620 | 180 | NO |
| R371 | R402H16 | 4K7R2J-2-GP | 63.47234.1DL | R402H16 | 3310 | 5705.8 | 270 | NO |
| R372 | R402H16 | 4K7R2J-2-GP | 63.47234.1DL | R402H16 | 3310 | 5786 | 270 | NO |
| R374 | R402H16 | 4K7R2J-2-GP | 63.47234.1DL | R402H16 | 2931 | 13885 | 180 | NO |
| R375 | R402H16 | 4K7R2J-2-GP | 63.47234.1DL | R402H16 | 2849 | 13885 | 180 | NO |
| R379 | R402H16 | 0R2J-2-GP | 63.R0034.1DL | R402H16 | 3485 | 1255 | 180 | NO |
| R380 | R402H16 | 0R2J-2-GP | 63.R0034.1DL | R402H16 | 8535 | 19358 | 270 | NO |
| R381 | R402H16 | 4K7R2J-2-GP | 63.47234.1DL | R402H16 | 3525 | 735 | 0 | NO |
| R382 | R402H16 | 0R2J-2-GP | 63.R0034.1DL | R402H16 | 3525 | 1255 | 180 | NO |
| R384 | R402H16 | 0R2J-2-GP | 63.R0034.1DL | R402H16 | 8535 | 19408 | 270 | NO |
| R385 | R402H16 | 0R2J-2-GP | 63.R0034.1DL | R402H16 | 8545 | 15375 | 270 | NO |
| R386 | R402H16 | 0R2J-2-GP | 63.R0034.1DL | R402H16 | 8545 | 15425 | 270 | NO |
| R387 | R402H16 | 10KR2F-2-GP | 64.10025.6DL | R402H16 | 3655 | 580 | 90 | NO |
| R388 | R402H16 | 10KR2F-2-GP | 64.10025.6DL | R402H16 | 3822 | 864 | 180 | NO |
| R389 | R402H16 | 2KR2F-3-GP | 64.20015.6DL | R402H16 | 3655 | 685 | 270 | NO |
| R390 | R402H16 | 2KR2F-3-GP | 64.20015.6DL | R402H16 | 3781 | 864 | 0 | NO |
| R391 | R402H16 | 0R2J-2-GP | 63.R0034.1DL | R402H16 | 8545 | 11320 | 270 | NO |
| R392 | R402H16 | 0R2J-2-GP | 63.R0034.1DL | R402H16 | 8545 | 11370 | 270 | NO |
| R393 | R402H16 | 0R2J-2-GP | 63.R0034.1DL | R402H16 | 8545 | 7265 | 270 | NO |
| R394 | R402H16 | 0R2J-2-GP | 63.R0034.1DL | R402H16 | 8545 | 7315 | 270 | NO |
| R395 | R402H16 | 0R2J-2-GP | 63.R0034.1DL | R402H16 | 8545 | 3210 | 270 | NO |
| R396 | R402H16 | 0R2J-2-GP | 63.R0034.1DL | R402H16 | 8545 | 3260 | 270 | NO |
| R397 | R402H16 | 0R2J-2-GP | 63.R0034.1DL | R402H16 | 1248 | 19341 | 270 | NO |
| R398 | R402H16 | 0R2J-2-GP | 63.R0034.1DL | R402H16 | 1248 | 19391 | 270 | NO |
| R399 | R402H16 | 0R2J-2-GP | 63.R0034.1DL | R402H16 | 1265 | 15375 | 270 | NO |
| R400 | R402H16 | 0R2J-2-GP | 63.R0034.1DL | R402H16 | 1265 | 15425 | 270 | NO |
| R401 | R402H16 | 0R2J-2-GP | 63.R0034.1DL | R402H16 | 1265 | 11320 | 270 | NO |
| R402 | R402H16 | 0R2J-2-GP | 63.R0034.1DL | R402H16 | 1265 | 11370 | 270 | NO |
| R403 | R402H16 | 0R2J-2-GP | 63.R0034.1DL | R402H16 | 1265 | 7265 | 270 | NO |
| R404 | R402H16 | 0R2J-2-GP | 63.R0034.1DL | R402H16 | 1265 | 7315 | 270 | NO |
| R405 | R402H16 | 0R2J-2-GP | 63.R0034.1DL | R402H16 | 1265 | 3210 | 270 | NO |
| R406 | R402H16 | 10KR2F-2-GP | 64.10025.6DL | R402H16 | 560 | 18825 | 0 | NO |
| R407 | R402H16 | 0R2J-2-GP | 63.R0034.1DL | R402H16 | 1265 | 3260 | 270 | NO |
| R408 | R402H16 | 0R2J-2-GP | 63.R0034.1DL | R402H16 | 1175 | 16710 | 90 | NO |
| R409 | R402H16 | 0R2J-2-GP | 63.R0034.1DL | R402H16 | 1175 | 16660 | 90 | NO |
| R410 | R402H16 | 0R2J-2-GP | 63.R0034.1DL | R402H16 | 1175 | 12655 | 90 | NO |
| R411 | R402H14 | 100R2J-2-GP | 63.10134.1DL | R402H14 | 520 | 18825 | 180 | NO |
| R412 | R402H16 | 0R2J-2-GP | 63.R0034.1DL | R402H16 | 1175 | 12605 | 90 | NO |
| R413 | R402H16 | 0R2J-2-GP | 63.R0034.1DL | R402H16 | 1175 | 8600 | 90 | NO |
| R414 | R402H16 | 0R2J-2-GP | 63.R0034.1DL | R402H16 | 1175 | 8550 | 90 | NO |
| R415 | R402H16 | 0R2J-2-GP | 63.R0034.1DL | R402H16 | 1175 | 4545 | 90 | NO |
| R416 | R402H16 | 0R2J-2-GP | 63.R0034.1DL | R402H16 | 1175 | 4495 | 90 | NO |
| R417 | R402H16 | 0R2J-2-GP | 63.R0034.1DL | R402H16 | 1143 | 675 | 180 | NO |
| R418 | R402H16 | 0R2J-2-GP | 63.R0034.1DL | R402H16 | 1193 | 675 | 180 | NO |
| R419 | R402H16 | 0R2J-2-GP | 63.R0034.1DL | R402H16 | 3325 | 16810 | 90 | NO |
| R420 | R402H16 | 0R2J-2-GP | 63.R0034.1DL | R402H16 | 3325 | 16850 | 90 | NO |
| R421 | R402H16 | 0R2J-2-GP | 63.R0034.1DL | R402H16 | 3325 | 11825 | 90 | NO |
| R422 | R402H16 | 0R2J-2-GP | 63.R0034.1DL | R402H16 | 3325 | 11865 | 90 | NO |
| R423 | R402H16 | 0R2J-2-GP | 63.R0034.1DL | R402H16 | 3325 | 8150 | 90 | NO |
| R424 | R402H16 | 0R2J-2-GP | 63.R0034.1DL | R402H16 | 3325 | 8110 | 90 | NO |
| R425 | R402H16 | 0R2J-2-GP | 63.R0034.1DL | R402H16 | 3325 | 3810 | 90 | NO |
| R426 | R402H16 | 0R2J-2-GP | 63.R0034.1DL | R402H16 | 3325 | 3850 | 90 | NO |
| R427 | R402H16 | 0R2J-2-GP | 63.R0034.1DL | R402H16 | 3220 | 5725 | 270 | NO |
| R428 | R402H16 | 0R2J-2-GP | 63.R0034.1DL | R402H16 | 3220 | 5765 | 270 | NO |
| R429 | R402H16 | 0R2J-2-GP | 63.R0034.1DL | R402H16 | 2870 | 13975 | 180 | NO |
| R430 | R402H16 | 0R2J-2-GP | 63.R0034.1DL | R402H16 | 2910 | 13975 | 180 | NO |
| R551 | R402H16 | 200KR2F-L-GP | 64.20035.6DL | R402H16 | 7843.39 | 19335.07 | 0 | NO |
| R552 | R402H16 | 200KR2F-L-GP | 64.20035.6DL | R402H16 | 8195 | 15595 | 0 | NO |
| R553 | R402H16 | 200KR2F-L-GP | 64.20035.6DL | R402H16 | 8195 | 11540 | 0 | NO |
| R554 | R402H16 | 200KR2F-L-GP | 64.20035.6DL | R402H16 | 8195 | 7485 | 0 | NO |
| R555 | R402H16 | 200KR2F-L-GP | 64.20035.6DL | R402H16 | 8195 | 3430 | 0 | NO |
| R556 | R402H16 | 200KR2F-L-GP | 64.20035.6DL | R402H16 | 610 | 19345 | 0 | NO |
| R557 | R402H16 | 200KR2F-L-GP | 64.20035.6DL | R402H16 | 905 | 15505 | 0 | NO |
| R558 | R402H16 | 200KR2F-L-GP | 64.20035.6DL | R402H16 | 912 | 11544 | 0 | NO |
| R559 | R402H16 | 200KR2F-L-GP | 64.20035.6DL | R402H16 | 912 | 7485 | 0 | NO |
| R560 | R402H16 | 200KR2F-L-GP | 64.20035.6DL | R402H16 | 912 | 3430 | 0 | NO |
| R561 | R402H16 | 200KR2F-L-GP | 64.20035.6DL | R402H16 | 1544 | 16491 | 180 | NO |
| R562 | R402H16 | 200KR2F-L-GP | 64.20035.6DL | R402H16 | 1532 | 12436 | 180 | NO |
| R563 | R402H16 | 200KR2F-L-GP | 64.20035.6DL | R402H16 | 1529 | 8381 | 180 | NO |
| R564 | R402H16 | 200KR2F-L-GP | 64.20035.6DL | R402H16 | 1529 | 4326 | 180 | NO |
| R566 | R402H16 | 300KR2F-GP | 64.30035.6DL | R402H16 | 7888.39 | 19335.07 | 180 | NO |
| R567 | R402H16 | 300KR2F-GP | 64.30035.6DL | R402H16 | 8240 | 15595 | 180 | NO |
| R568 | R402H16 | 300KR2F-GP | 64.30035.6DL | R402H16 | 8240 | 11540 | 180 | NO |
| R569 | R402H16 | 300KR2F-GP | 64.30035.6DL | R402H16 | 8240 | 7485 | 180 | NO |
| R570 | R402H16 | 300KR2F-GP | 64.30035.6DL | R402H16 | 8240 | 3430 | 180 | NO |
| R571 | R402H16 | 300KR2F-GP | 64.30035.6DL | R402H16 | 655 | 19345 | 180 | NO |
| R572 | R402H16 | 300KR2F-GP | 64.30035.6DL | R402H16 | 950 | 15505 | 180 | NO |
| R573 | R402H16 | 300KR2F-GP | 64.30035.6DL | R402H16 | 957 | 11544 | 180 | NO |
| R574 | R402H16 | 300KR2F-GP | 64.30035.6DL | R402H16 | 957 | 7485 | 180 | NO |
| R575 | R402H16 | 300KR2F-GP | 64.30035.6DL | R402H16 | 957 | 3430 | 180 | NO |
| R576 | R402H16 | 300KR2F-GP | 64.30035.6DL | R402H16 | 1499 | 16491 | 0 | NO |
| R577 | R402H16 | 300KR2F-GP | 64.30035.6DL | R402H16 | 1487 | 12436 | 0 | NO |
| R579 | R2010H28 | 2R2010J-1-GP | 63.2R037.18L | R2010H28 | 411 | 16244 | 0 | NO |
| R580 | R402H16 | 300KR2F-GP | 64.30035.6DL | R402H16 | 1484 | 8381 | 0 | NO |
| R581 | R402H16 | 300KR2F-GP | 64.30035.6DL | R402H16 | 1484 | 4326 | 0 | NO |
| R582 | R402H16 | 200KR2F-L-GP | 64.20035.6DL | R402H16 | 2015 | 585 | 180 | NO |
| R583 | R402H16 | 300KR2F-GP | 64.30035.6DL | R402H16 | 1970 | 585 | 0 | NO |
| R584 | R2010H28 | 2R2010J-1-GP | 63.2R037.18L | R2010H28 | 317.07 | 10720.41 | 180 | NO |
| R9033 | R402H16 | 4K7R2F-GP | 64.47015.6DL | R402H16 | 3325 | 16730 | 270 | NO |
| R9034 | R402H16 | 4K7R2F-GP | 64.47015.6DL | R402H16 | 3365 | 16950 | 270 | NO |
| R9035 | R402H16 | 0R2J-2-GP | 63.R0034.1DL | R402H16 | 450 | 10625 | 180 | NO |
| R9036 | R402H16 | 0R2J-2-GP | 63.R0034.1DL | R402H16 | 480 | 18825 | 180 | NO |
| R9037 | R402H16 | 4K7R2F-GP | 64.47015.6DL | R402H16 | 3325 | 11745 | 270 | NO |
| R9038 | R402H16 | 0R2J-2-GP | 63.R0034.1DL | R402H16 | 410 | 10625 | 180 | NO |
| R9055 | R402H16 | 27R2F-GP | 64.27R05.6DL | R402H16 | 4040 | 17210 | 90 | NO |
| R9056 | R402H16 | 27R2F-GP | 64.27R05.6DL | R402H16 | 4040 | 17250 | 90 | NO |
| R9057 | R402H16 | 27R2F-GP | 64.27R05.6DL | R402H16 | 4040 | 17060 | 90 | NO |
| R9058 | R402H16 | 27R2F-GP | 64.27R05.6DL | R402H16 | 4040 | 17100 | 90 | NO |
| R9059 | R402H16 | 27R2F-GP | 64.27R05.6DL | R402H16 | 3445 | 4340 | 180 | NO |
| R9060 | R402H16 | 27R2F-GP | 64.27R05.6DL | R402H16 | 3405 | 4340 | 180 | NO |
| R9061 | R402H16 | 27R2F-GP | 64.27R05.6DL | R402H16 | 3595 | 4340 | 180 | NO |
| R9062 | R402H16 | 27R2F-GP | 64.27R05.6DL | R402H16 | 3555 | 4340 | 180 | NO |
| R9063 | R402H16 | 27R2F-GP | 64.27R05.6DL | R402H16 | 3445 | 17340 | 180 | NO |
| R9064 | R402H16 | 27R2F-GP | 64.27R05.6DL | R402H16 | 3405 | 17340 | 180 | NO |
| R9065 | R402H16 | 27R2F-GP | 64.27R05.6DL | R402H16 | 3595 | 17340 | 180 | NO |
| R9066 | R402H16 | 27R2F-GP | 64.27R05.6DL | R402H16 | 3555 | 17340 | 180 | NO |
| R9067 | R402H16 | 27R2F-GP | 64.27R05.6DL | R402H16 | 3800 | 11675 | 0 | NO |
| R9068 | R402H16 | 27R2F-GP | 64.27R05.6DL | R402H16 | 3555 | 16660 | 0 | NO |
| R9069 | R402H16 | 27R2F-GP | 64.27R05.6DL | R402H16 | 3405 | 16660 | 0 | NO |
| R9070 | R402H16 | 27R2F-GP | 64.27R05.6DL | R402H16 | 3595 | 16660 | 0 | NO |
| R9071 | R402H16 | 27R2F-GP | 64.27R05.6DL | R402H16 | 4040 | 12225 | 90 | NO |
| R9072 | R402H16 | 27R2F-GP | 64.27R05.6DL | R402H16 | 3445 | 16660 | 0 | NO |
| R9073 | R402H16 | 27R2F-GP | 64.27R05.6DL | R402H16 | 4040 | 12265 | 90 | NO |
| R9074 | R402H16 | 27R2F-GP | 64.27R05.6DL | R402H16 | 4040 | 12075 | 90 | NO |
| R9075 | R402H16 | 27R2F-GP | 64.27R05.6DL | R402H16 | 4040 | 12115 | 90 | NO |
| R9076 | R402H16 | 27R2F-GP | 64.27R05.6DL | R402H16 | 3910 | 11675 | 0 | NO |
| R9077 | R402H16 | 27R2F-GP | 64.27R05.6DL | R402H16 | 3950 | 11675 | 0 | NO |
| R9078 | R402H16 | 27R2F-GP | 64.27R05.6DL | R402H16 | 3760 | 11675 | 0 | NO |
| R9079 | R402H16 | 27R2F-GP | 64.27R05.6DL | R402H16 | 3555 | 12355 | 180 | NO |
| R9080 | R402H16 | 27R2F-GP | 64.27R05.6DL | R402H16 | 3555 | 8640 | 180 | NO |
| R9081 | R402H16 | 27R2F-GP | 64.27R05.6DL | R402H16 | 4040 | 8200 | 90 | NO |
| R9082 | R402H16 | 27R2F-GP | 64.27R05.6DL | R402H16 | 4040 | 8050 | 90 | NO |
| R9083 | R402H16 | 27R2F-GP | 64.27R05.6DL | R402H16 | 4040 | 8240 | 90 | NO |
| R9084 | R402H16 | 27R2F-GP | 64.27R05.6DL | R402H16 | 3845 | 7960 | 0 | NO |
| R9085 | R402H16 | 27R2F-GP | 64.27R05.6DL | R402H16 | 4040 | 8090 | 90 | NO |
| R9086 | R402H16 | 27R2F-GP | 64.27R05.6DL | R402H16 | 3885 | 7960 | 0 | NO |
| R9087 | R402H16 | 27R2F-GP | 64.27R05.6DL | R402H16 | 3695 | 7960 | 0 | NO |
| R9088 | R402H16 | 27R2F-GP | 64.27R05.6DL | R402H16 | 3735 | 7960 | 0 | NO |
| R9089 | R402H16 | 27R2F-GP | 64.27R05.6DL | R402H16 | 3405 | 8640 | 180 | NO |
| R9090 | R402H16 | 27R2F-GP | 64.27R05.6DL | R402H16 | 3445 | 8640 | 180 | NO |
| R9091 | R402H16 | 27R2F-GP | 64.27R05.6DL | R402H16 | 3595 | 8640 | 180 | NO |
| R9092 | R402H16 | 4K7R2F-GP | 64.47015.6DL | R402H16 | 3325 | 11785 | 90 | NO |
| R9093 | R402H16 | 4K7R2F-GP | 64.47015.6DL | R402H16 | 3365 | 11945 | 270 | NO |
| R9094 | R402H16 | 27R2F-GP | 64.27R05.6DL | R402H16 | 3800 | 8640 | 180 | NO |
| R9095 | R402H16 | 27R2F-GP | 64.27R05.6DL | R402H16 | 3950 | 8640 | 180 | NO |
| R9096 | R402H16 | 27R2F-GP | 64.27R05.6DL | R402H16 | 3760 | 8640 | 180 | NO |
| R9097 | R402H16 | 27R2F-GP | 64.27R05.6DL | R402H16 | 3800 | 12355 | 180 | NO |
| R9098 | R402H16 | 27R2F-GP | 64.27R05.6DL | R402H16 | 3910 | 8640 | 180 | NO |
| R9099 | R402H16 | 27R2F-GP | 64.27R05.6DL | R402H16 | 3760 | 12355 | 180 | NO |
| R9100 | R402H16 | 27R2F-GP | 64.27R05.6DL | R402H16 | 3950 | 12355 | 180 | NO |
| R9101 | R402H16 | 27R2F-GP | 64.27R05.6DL | R402H16 | 3910 | 12355 | 180 | NO |
| R9102 | R402H16 | 27R2F-GP | 64.27R05.6DL | R402H16 | 3445 | 12355 | 180 | NO |
| R9103 | R402H16 | 27R2F-GP | 64.27R05.6DL | R402H16 | 3405 | 12355 | 180 | NO |
| R9104 | R402H16 | 27R2F-GP | 64.27R05.6DL | R402H16 | 3595 | 12355 | 180 | NO |
| R9118 | R402H16 | 4K7R2F-GP | 64.47015.6DL | R402H16 | 3325 | 8030 | 270 | NO |
| R9119 | R402H16 | 4K7R2F-GP | 64.47015.6DL | R402H16 | 3365 | 8190 | 90 | NO |
| R9120 | R402H16 | 27R2F-GP | 64.27R05.6DL | R402H16 | 3445 | 3660 | 0 | NO |
| R9121 | R402H16 | 4K7R2F-GP | 64.47015.6DL | R402H16 | 3365 | 3890 | 90 | NO |
| R9122 | R402H16 | 4K7R2F-GP | 64.47015.6DL | R402H16 | 3325 | 3730 | 270 | NO |
| R9123 | R402H16 | 27R2F-GP | 64.27R05.6DL | R402H16 | 3595 | 3660 | 0 | NO |
| R9124 | R402H16 | 27R2F-GP | 64.27R05.6DL | R402H16 | 3405 | 3660 | 0 | NO |
| R9125 | R402H16 | 27R2F-GP | 64.27R05.6DL | R402H16 | 3800 | 3660 | 0 | NO |
| R9126 | R402H16 | 27R2F-GP | 64.27R05.6DL | R402H16 | 3950 | 3660 | 0 | NO |
| R9127 | R402H16 | 27R2F-GP | 64.27R05.6DL | R402H16 | 3555 | 3660 | 0 | NO |
| R9128 | R402H16 | 27R2F-GP | 64.27R05.6DL | R402H16 | 3760 | 3660 | 0 | NO |
| R9129 | R402H16 | 27R2F-GP | 64.27R05.6DL | R402H16 | 3910 | 3660 | 0 | NO |
| R9130 | R402H16 | 27R2F-GP | 64.27R05.6DL | R402H16 | 3950 | 4340 | 180 | NO |
| R9131 | R402H16 | 27R2F-GP | 64.27R05.6DL | R402H16 | 3910 | 4340 | 180 | NO |
| R9132 | R402H16 | 27R2F-GP | 64.27R05.6DL | R402H16 | 3760 | 4340 | 180 | NO |
| R9133 | R402H16 | 27R2F-GP | 64.27R05.6DL | R402H16 | 3800 | 4340 | 180 | NO |
| R9234 | R402H16 | 0R2J-2-GP | 63.R0034.1DL | R402H16 | 9025 | 17290 | 0 | NO |
| R9239 | R2010H26 | 2R2010F-GP | 64.2R005.F9L | R2010H26 | 8625 | 19655 | 0 | NO |
| R9241 | R2010H26 | 2R2010F-GP | 64.2R005.F9L | R2010H26 | 757 | 16240 | 180 | NO |
| R9242 | R2010H26 | 2R2010F-GP | 64.2R005.F9L | R2010H26 | 1696 | 3683 | 0 | NO |
| R9243 | R2010H26 | 2R2010F-GP | 64.2R005.F9L | R2010H26 | 9028 | 11806 | 0 | NO |
| R9244 | R2010H26 | 2R2010F-GP | 64.2R005.F9L | R2010H26 | 8990 | 3686 | 0 | NO |
| R9245 | R2010H26 | 2R2010F-GP | 64.2R005.F9L | R2010H26 | 1342 | 19652 | 0 | NO |
| R9246 | R2010H26 | 2R2010F-GP | 64.2R005.F9L | R2010H26 | 768 | 4072 | 180 | NO |
| R9247 | R2010H26 | 2R2010F-GP | 64.2R005.F9L | R2010H26 | 1698 | 7754 | 0 | NO |
| R9248 | R2010H26 | 2R2010F-GP | 64.2R005.F9L | R2010H26 | 9013 | 15846 | 0 | NO |
| R9249 | R2010H26 | 2R2010F-GP | 64.2R005.F9L | R2010H26 | 1054 | 331 | 270 | NO |
| R9250 | R2010H26 | 2R2010F-GP | 64.2R005.F9L | R2010H26 | 1693 | 11795 | 0 | NO |
| R9251 | R2010H26 | 2R2010F-GP | 64.2R005.F9L | R2010H26 | 1704 | 15857 | 0 | NO |
| R9252 | R2010H26 | 2R2010F-GP | 64.2R005.F9L | R2010H26 | 794 | 8132 | 180 | NO |
| R9260 | R2010H26 | 2R2010F-GP | 64.2R005.F9L | R2010H26 | 774 | 12187 | 180 | NO |
| R9261 | R2010H26 | 2R2010F-GP | 64.2R005.F9L | R2010H26 | 8987 | 7746 | 0 | NO |
| R9349 | R402H16 | 2D2R2F-GP | 64.2R205.6DL | R402H16 | 3265 | 17043 | 90 | NO |
| R9350 | R402H16 | 2D2R2F-GP | 64.2R205.6DL | R402H16 | 3265 | 17250 | 90 | NO |
| R9351 | R402H16 | 2D2R2F-GP | 64.2R205.6DL | R402H16 | 3265 | 12058 | 90 | NO |
| R9352 | R402H16 | 2D2R2F-GP | 64.2R205.6DL | R402H16 | 3265 | 12265 | 90 | NO |
| R9355 | R402H16 | 2D2R2F-GP | 64.2R205.6DL | R402H16 | 3265 | 8344 | 90 | NO |
| R9356 | R402H16 | 2D2R2F-GP | 64.2R205.6DL | R402H16 | 3265 | 8550 | 90 | NO |
| R9357 | R402H16 | 2D2R2F-GP | 64.2R205.6DL | R402H16 | 3265 | 4044 | 90 | NO |
| R9358 | R402H16 | 2D2R2F-GP | 64.2R205.6DL | R402H16 | 3265 | 4250 | 90 | NO |
| R9394 | R402H14 | 100R2J-2-GP | 63.10134.1DL | R402H14 | 1940 | 1625 | 270 | NO |
| R9395 | R402H16 | 4K7R2J-2-GP | 63.47234.1DL | R402H16 | 3465 | 3410 | 270 | NO |
| R9400 | R402H16 | 330R2F-GP | 64.33005.6DL | R402H16 | 9215 | 9754.77 | 270 | NO |
| R9401 | R402H14 | 100R2J-2-GP | 63.10134.1DL | R402H14 | 9215 | 9710 | 270 | NO |
| R9402 | R402H16 | 4K7R2J-2-GP | 63.47234.1DL | R402H16 | 3820 | 11425 | 270 | NO |
| R9407 | R402H16 | 330R2F-GP | 64.33005.6DL | R402H16 | 9215 | 1644.53 | 270 | NO |
| R9408 | R402H14 | 100R2J-2-GP | 63.10134.1DL | R402H14 | 9215 | 1600 | 270 | NO |
| R9409 | R402H16 | 4K7R2J-2-GP | 63.47234.1DL | R402H16 | 3755 | 7710 | 270 | NO |
| R9414 | R402H16 | 330R2F-GP | 64.33005.6DL | R402H16 | 1930 | 17905 | 270 | NO |
| R9415 | R402H14 | 100R2J-2-GP | 63.10134.1DL | R402H14 | 1930 | 17860 | 270 | NO |
| R9416 | R402H16 | 4K7R2J-2-GP | 63.47234.1DL | R402H16 | 3535 | 17590 | 90 | NO |
| R9421 | R402H16 | 330R2F-GP | 64.33005.6DL | R402H16 | 945 | 6155 | 270 | NO |
| R9422 | R402H14 | 100R2J-2-GP | 63.10134.1DL | R402H14 | 945 | 6110 | 270 | NO |
| R9423 | R402H16 | 4K7R2J-2-GP | 63.47234.1DL | R402H16 | 3535 | 4590 | 90 | NO |
| R9428 | R402H16 | 330R2F-GP | 64.33005.6DL | R402H16 | 1935 | 5735 | 270 | NO |
| R9429 | R402H14 | 100R2J-2-GP | 63.10134.1DL | R402H14 | 1935 | 5690 | 270 | NO |
| R9430 | R402H16 | 4K7R2J-2-GP | 63.47234.1DL | R402H16 | 3890 | 4590 | 90 | NO |
| R9435 | R402H16 | 330R2F-GP | 64.33005.6DL | R402H16 | 945 | 14265 | 270 | NO |
| R9436 | R402H14 | 100R2J-2-GP | 63.10134.1DL | R402H14 | 945 | 14220 | 270 | NO |
| R9437 | R402H16 | 4K7R2J-2-GP | 63.47234.1DL | R402H16 | 3535 | 12605 | 90 | NO |
| R9442 | R402H16 | 330R2F-GP | 64.33005.6DL | R402H16 | 9215 | 5699.65 | 270 | NO |
| R9443 | R402H14 | 100R2J-2-GP | 63.10134.1DL | R402H14 | 9215 | 5655 | 270 | NO |
| R9444 | R402H16 | 4K7R2J-2-GP | 63.47234.1DL | R402H16 | 4290 | 8110 | 0 | NO |
| R9449 | R402H16 | 330R2F-GP | 64.33005.6DL | R402H16 | 9215 | 13809.88 | 270 | NO |
| R9450 | R402H14 | 100R2J-2-GP | 63.10134.1DL | R402H14 | 9215 | 13765 | 270 | NO |
| R9451 | R402H16 | 4K7R2J-2-GP | 63.47234.1DL | R402H16 | 4290 | 12135 | 0 | NO |
| R9452 | R402H14 | 10R2F-L-GP | 64.10R05.6DL | R402H14 | 4230 | 12120 | 270 | NO |
| R9456 | R402H16 | 330R2F-GP | 64.33005.6DL | R402H16 | 945 | 2100 | 270 | NO |
| R9457 | R402H14 | 100R2J-2-GP | 63.10134.1DL | R402H14 | 945 | 2055 | 270 | NO |
| R9458 | R402H16 | 4K7R2J-2-GP | 63.47234.1DL | R402H16 | 3820 | 3410 | 270 | NO |
| R9463 | R402H16 | 330R2F-GP | 64.33005.6DL | R402H16 | 1940 | 9785 | 270 | NO |
| R9464 | R402H14 | 100R2J-2-GP | 63.10134.1DL | R402H14 | 1940 | 9740 | 270 | NO |
| R9465 | R402H16 | 4K7R2J-2-GP | 63.47234.1DL | R402H16 | 3890 | 8890 | 90 | NO |
| R9470 | R402H16 | 330R2F-GP | 64.33005.6DL | R402H16 | 1885 | 13820 | 270 | NO |
| R9471 | R402H14 | 100R2J-2-GP | 63.10134.1DL | R402H14 | 1885 | 13775 | 270 | NO |
| R9472 | R402H16 | 4K7R2J-2-GP | 63.47234.1DL | R402H16 | 3890 | 12605 | 90 | NO |
| R9477 | R402H16 | 330R2F-GP | 64.33005.6DL | R402H16 | 945 | 10210 | 270 | NO |
| R9478 | R402H14 | 100R2J-2-GP | 63.10134.1DL | R402H14 | 945 | 10165 | 270 | NO |
| R9479 | R402H16 | 4K7R2J-2-GP | 63.47234.1DL | R402H16 | 3535 | 8890 | 90 | NO |
| R9488 | R402H16 | 4K7R2J-2-GP | 63.47234.1DL | R402H16 | 3900 | 11425 | 270 | NO |
| R9490 | R402H16 | 4K7R2J-2-GP | 63.47234.1DL | R402H16 | 4290 | 8190 | 0 | NO |
| R9492 | R402H16 | 4K7R2J-2-GP | 63.47234.1DL | R402H16 | 4290 | 12215 | 0 | NO |
| R9493 | R402H16 | 330R2F-GP | 64.33005.6DL | R402H16 | 1940 | 1670 | 270 | NO |
| R9494 | R402H14 | 10R2F-L-GP | 64.10R05.6DL | R402H14 | 4230 | 12200 | 270 | NO |
| R9495 | R402H16 | 4K7R2J-2-GP | 63.47234.1DL | R402H16 | 7647.39 | 19615.07 | 180 | NO |
| R9496 | R402H16 | 4K7R2J-2-GP | 63.47234.1DL | R402H16 | 3835 | 7710 | 270 | NO |
| R9499 | R402H16 | 4K7R2J-2-GP | 63.47234.1DL | R402H16 | 8165 | 15875 | 180 | NO |
| R9500 | R402H16 | 4K7R2J-2-GP | 63.47234.1DL | R402H16 | 3455 | 17590 | 90 | NO |
| R9501 | R402H16 | 4K7R2J-2-GP | 63.47234.1DL | R402H16 | 8165 | 11820 | 180 | NO |
| R9502 | R402H16 | 4K7R2J-2-GP | 63.47234.1DL | R402H16 | 3810 | 12605 | 90 | NO |
| R9503 | R402H16 | 4K7R2J-2-GP | 63.47234.1DL | R402H16 | 8165 | 7765 | 180 | NO |
| R9504 | R402H16 | 4K7R2J-2-GP | 63.47234.1DL | R402H16 | 3810 | 8890 | 90 | NO |
| R9505 | R402H16 | 4K7R2J-2-GP | 63.47234.1DL | R402H16 | 3810 | 4590 | 90 | NO |
| R9506 | R402H16 | 4K7R2J-2-GP | 63.47234.1DL | R402H16 | 8165 | 3710 | 180 | NO |
| R9507 | R402H16 | 4K7R2J-2-GP | 63.47234.1DL | R402H16 | 3545 | 3410 | 270 | NO |
| R9508 | R402H16 | 4K7R2J-2-GP | 63.47234.1DL | R402H16 | 373 | 19623 | 180 | NO |
| R9509 | R402H16 | 4K7R2F-GP | 64.47015.6DL | R402H16 | 3990 | 8405 | 270 | NO |
| R9510 | R402H16 | 4K7R2F-GP | 64.47015.6DL | R402H16 | 3980 | 4085 | 0 | NO |
| R9511 | R402H16 | 4K7R2F-GP | 64.47015.6DL | R402H16 | 3790 | 17310 | 0 | NO |
| R9512 | R402H16 | 4K7R2F-GP | 64.47015.6DL | R402H16 | 4005 | 11920 | 270 | NO |
| R9515 | R402H16 | 4K7R2J-2-GP | 63.47234.1DL | R402H16 | 3455 | 12605 | 90 | NO |
| R9516 | R402H16 | 4K7R2J-2-GP | 63.47234.1DL | R402H16 | 793.75 | 15818.75 | 180 | NO |
| R9517 | R402H16 | 4K7R2J-2-GP | 63.47234.1DL | R402H16 | 3455 | 8890 | 90 | NO |
| R9582 | R805H24 | 0R5J-L1-GP | 63.R0031.L0L | R805H24 | 3880 | 17325 | 0 | NO |
| R9583 | R805H24 | 0R5J-L1-GP | 63.R0031.L0L | R805H24 | 4045 | 12325 | 270 | NO |
| R9584 | R805H24 | 0R5J-L1-GP | 63.R0031.L0L | R805H24 | 4025 | 8505 | 270 | NO |
| R9585 | R805H24 | 0R5J-L1-GP | 63.R0031.L0L | R805H24 | 4025 | 4205 | 270 | NO |
| R9587 | R402H16 | 4K7R2J-2-GP | 63.47234.1DL | R402H16 | 3455 | 4590 | 90 | NO |
| R9589 | R402H16 | 4K7R2J-2-GP | 63.47234.1DL | R402H16 | 3900 | 3410 | 270 | NO |
| R9590 | R402H14 | 10R2F-L-GP | 64.10R05.6DL | R402H14 | 4230 | 17105 | 270 | NO |
| R9591 | R402H14 | 10R2F-L-GP | 64.10R05.6DL | R402H14 | 4230 | 17185 | 270 | NO |
| R9592 | R402H14 | 10R2F-L-GP | 64.10R05.6DL | R402H14 | 3805 | 11485 | 180 | NO |
| R9593 | R402H14 | 10R2F-L-GP | 64.10R05.6DL | R402H14 | 3885 | 11485 | 180 | NO |
| R9594 | R402H14 | 10R2F-L-GP | 64.10R05.6DL | R402H14 | 4230 | 8095 | 270 | NO |
| R9595 | R402H14 | 10R2F-L-GP | 64.10R05.6DL | R402H14 | 4230 | 8175 | 270 | NO |
| R9596 | R402H14 | 10R2F-L-GP | 64.10R05.6DL | R402H14 | 3740 | 7770 | 180 | NO |
| R9597 | R402H14 | 10R2F-L-GP | 64.10R05.6DL | R402H14 | 3820 | 7770 | 180 | NO |
| R9598 | R402H14 | 10R2F-L-GP | 64.10R05.6DL | R402H14 | 3550 | 17530 | 0 | NO |
| R9599 | R402H14 | 10R2F-L-GP | 64.10R05.6DL | R402H14 | 3470 | 17530 | 0 | NO |
| R9600 | R402H14 | 10R2F-L-GP | 64.10R05.6DL | R402H14 | 3905 | 12545 | 0 | NO |
| R9601 | R402H14 | 10R2F-L-GP | 64.10R05.6DL | R402H14 | 3825 | 12545 | 0 | NO |
| R9602 | R402H14 | 10R2F-L-GP | 64.10R05.6DL | R402H14 | 3905 | 8830 | 0 | NO |
| R9603 | R402H14 | 10R2F-L-GP | 64.10R05.6DL | R402H14 | 3825 | 8830 | 0 | NO |
| R9604 | R402H14 | 10R2F-L-GP | 64.10R05.6DL | R402H14 | 3905 | 4530 | 0 | NO |
| R9605 | R402H14 | 10R2F-L-GP | 64.10R05.6DL | R402H14 | 3825 | 4530 | 0 | NO |
| R9606 | R402H14 | 10R2F-L-GP | 64.10R05.6DL | R402H14 | 3450 | 3470 | 180 | NO |
| R9607 | R402H14 | 10R2F-L-GP | 64.10R05.6DL | R402H14 | 3530 | 3470 | 180 | NO |
| R9608 | R402H14 | 10R2F-L-GP | 64.10R05.6DL | R402H14 | 3450 | 16470 | 180 | NO |
| R9609 | R402H14 | 10R2F-L-GP | 64.10R05.6DL | R402H14 | 3530 | 16470 | 180 | NO |
| R9610 | R402H14 | 10R2F-L-GP | 64.10R05.6DL | R402H14 | 3550 | 12545 | 0 | NO |
| R9611 | R402H14 | 10R2F-L-GP | 64.10R05.6DL | R402H14 | 3470 | 12545 | 0 | NO |
| R9612 | R402H14 | 10R2F-L-GP | 64.10R05.6DL | R402H14 | 3470 | 8830 | 0 | NO |
| R9613 | R402H14 | 10R2F-L-GP | 64.10R05.6DL | R402H14 | 3550 | 8830 | 0 | NO |
| R9614 | R402H14 | 10R2F-L-GP | 64.10R05.6DL | R402H14 | 3550 | 4530 | 0 | NO |
| R9615 | R402H14 | 10R2F-L-GP | 64.10R05.6DL | R402H14 | 3470 | 4530 | 0 | NO |
| R9616 | R402H14 | 10R2F-L-GP | 64.10R05.6DL | R402H14 | 3805 | 3470 | 180 | NO |
| R9617 | R402H14 | 10R2F-L-GP | 64.10R05.6DL | R402H14 | 3885 | 3470 | 180 | NO |
| R9618 | R402H16 | 4K7R2J-2-GP | 63.47234.1DL | R402H16 | 900 | 11820 | 180 | NO |
| R9619 | R402H16 | 4K7R2J-2-GP | 63.47234.1DL | R402H16 | 900 | 7765 | 180 | NO |
| R9750 | R402H16 | 4K7R2J-2-GP | 63.47234.1DL | R402H16 | 900 | 3710 | 180 | NO |
| R9751 | R402H16 | 4K7R2J-2-GP | 63.47234.1DL | R402H16 | 1540 | 16210 | 0 | NO |
| R9752 | R402H16 | 4K7R2J-2-GP | 63.47234.1DL | R402H16 | 1540 | 12155 | 0 | NO |
| R9753 | R402H16 | 4K7R2J-2-GP | 63.47234.1DL | R402H16 | 1540 | 8100 | 0 | NO |
| R9754 | R402H16 | 4K7R2J-2-GP | 63.47234.1DL | R402H16 | 1536.25 | 4041.25 | 0 | NO |
| R9755 | R402H16 | 4K7R2J-2-GP | 63.47234.1DL | R402H16 | 2045 | 305 | 0 | NO |
| R9756 | R402H16 | 4K7R2F-GP | 64.47015.6DL | R402H16 | 9105 | 17295 | 0 | NO |
| R9757 | R402H16 | 0R2J-2-GP | 63.R0034.1DL | R402H16 | 3820 | 1030 | 180 | NO |
| R9758 | R402H16 | 1KR2J-1-GP | 63.10234.1DL | R402H16 | 3775 | 1030 | 0 | NO |
| R9760 | R402H16 | 4K7R2J-2-GP | 63.47234.1DL | R402H16 | 7692.39 | 19615.07 | 0 | NO |
| R9761 | R402H16 | 4K7R2J-2-GP | 63.47234.1DL | R402H16 | 8210 | 15875 | 0 | NO |
| R9762 | R402H16 | 4K7R2J-2-GP | 63.47234.1DL | R402H16 | 8210 | 11820 | 0 | NO |
| R9763 | R402H16 | 4K7R2J-2-GP | 63.47234.1DL | R402H16 | 8210 | 7765 | 0 | NO |
| R9764 | R402H16 | 4K7R2J-2-GP | 63.47234.1DL | R402H16 | 8210 | 3710 | 0 | NO |
| R9765 | R402H16 | 4K7R2J-2-GP | 63.47234.1DL | R402H16 | 418 | 19623 | 0 | NO |
| R9766 | R402H16 | 4K7R2J-2-GP | 63.47234.1DL | R402H16 | 838.75 | 15818.75 | 0 | NO |
| R9767 | R402H16 | 4K7R2J-2-GP | 63.47234.1DL | R402H16 | 945 | 11820 | 0 | NO |
| R9768 | R402H16 | 4K7R2J-2-GP | 63.47234.1DL | R402H16 | 945 | 7765 | 0 | NO |
| R9769 | R402H16 | 4K7R2J-2-GP | 63.47234.1DL | R402H16 | 945 | 3710 | 0 | NO |
| R9770 | R402H16 | 4K7R2J-2-GP | 63.47234.1DL | R402H16 | 1495 | 16210 | 180 | NO |
| R9771 | R402H16 | 4K7R2J-2-GP | 63.47234.1DL | R402H16 | 1495 | 12155 | 180 | NO |
| R9772 | R402H16 | 4K7R2J-2-GP | 63.47234.1DL | R402H16 | 1495 | 8100 | 180 | NO |
| R9773 | R402H16 | 4K7R2J-2-GP | 63.47234.1DL | R402H16 | 1491.25 | 4041.25 | 180 | NO |
| R9774 | R402H16 | 4K7R2J-2-GP | 63.47234.1DL | R402H16 | 2000 | 305 | 180 | NO |
| R9775 | R805H24 | 2K2R5F-GP | 64.22015.16L | R805H24 | 8153.39 | 19632.07 | 0 | NO |
| R9776 | R402H16 | 1KR2J-1-GP | 63.10234.1DL | R402H16 | 7619.14 | 19682.82 | 90 | NO |
| R9777 | R402H16 | 47KR2J-2-GP | 63.47334.1DL | R402H16 | 7883.89 | 19626.57 | 180 | NO |
| R9781 | R402H16 | 0R2J-2-GP | 63.R0034.1DL | R402H16 | 9215 | 17520 | 90 | NO |
| R9782 | R402H16 | 0R2J-2-GP | 63.R0034.1DL | R402H16 | 8862.5 | 17732.5 | 90 | NO |
| R9783 | R402H16 | 0R2J-2-GP | 63.R0034.1DL | R402H16 | 9080 | 17685 | 270 | NO |
| R9784 | R805H24 | 2K2R5F-GP | 64.22015.16L | R805H24 | 8701 | 15944 | 270 | NO |
| R9785 | R402H16 | 1KR2J-1-GP | 63.10234.1DL | R402H16 | 8136.75 | 15942.75 | 90 | NO |
| R9786 | R402H16 | 47KR2J-2-GP | 63.47334.1DL | R402H16 | 8401.5 | 15886.5 | 180 | NO |
| R9787 | R402H16 | 0R2J-2-GP | 63.R0034.1DL | R402H16 | 9215 | 13464.88 | 90 | NO |
| R9788 | R402H16 | 0R2J-2-GP | 63.R0034.1DL | R402H16 | 8856.8799999999992 | 13652 | 90 | NO |
| R9789 | R402H16 | 0R2J-2-GP | 63.R0034.1DL | R402H16 | 9080 | 13629.88 | 270 | NO |
| R9792 | R805H24 | 2K2R5F-GP | 64.22015.16L | R805H24 | 8701 | 11874 | 270 | NO |
| R9793 | R402H16 | 1KR2J-1-GP | 63.10234.1DL | R402H16 | 8136.75 | 11887.75 | 90 | NO |
| R9794 | R402H16 | 47KR2J-2-GP | 63.47334.1DL | R402H16 | 8401.5 | 11831.5 | 180 | NO |
| R9795 | R402H16 | 0R2J-2-GP | 63.R0034.1DL | R402H16 | 9215 | 9409.77 | 90 | NO |
| R9796 | R402H16 | 0R2J-2-GP | 63.R0034.1DL | R402H16 | 8862.5 | 9622.27 | 90 | NO |
| R9797 | R402H16 | 0R2J-2-GP | 63.R0034.1DL | R402H16 | 9080 | 9574.77 | 270 | NO |
| R9798 | R805H24 | 2K2R5F-GP | 64.22015.16L | R805H24 | 8701 | 7819 | 270 | NO |
| R9799 | R402H16 | 1KR2J-1-GP | 63.10234.1DL | R402H16 | 8136.75 | 7832.75 | 90 | NO |
| R9800 | R402H16 | 47KR2J-2-GP | 63.47334.1DL | R402H16 | 8401.5 | 7776.5 | 180 | NO |
| R9801 | R402H16 | 0R2J-2-GP | 63.R0034.1DL | R402H16 | 9215 | 5354.65 | 90 | NO |
| R9802 | R402H16 | 0R2J-2-GP | 63.R0034.1DL | R402H16 | 8862.5 | 5567.15 | 90 | NO |
| R9803 | R402H16 | 0R2J-2-GP | 63.R0034.1DL | R402H16 | 9080 | 5519.65 | 270 | NO |
| R9804 | R805H24 | 2K2R5F-GP | 64.22015.16L | R805H24 | 8706 | 3764 | 270 | NO |
| R9805 | R402H16 | 1KR2J-1-GP | 63.10234.1DL | R402H16 | 8136.75 | 3777.75 | 90 | NO |
| R9806 | R402H16 | 47KR2J-2-GP | 63.47334.1DL | R402H16 | 8401.5 | 3721.5 | 180 | NO |
| R9807 | R402H16 | 0R2J-2-GP | 63.R0034.1DL | R402H16 | 9215 | 1299.53 | 90 | NO |
| R9808 | R402H16 | 0R2J-2-GP | 63.R0034.1DL | R402H16 | 8880 | 1570 | 90 | NO |
| R9809 | R402H16 | 0R2J-2-GP | 63.R0034.1DL | R402H16 | 9090 | 1464.53 | 270 | NO |
| R9812 | R805H24 | 2K2R5F-GP | 64.22015.16L | R805H24 | 872 | 19642 | 0 | NO |
| R9813 | R402H16 | 1KR2J-1-GP | 63.10234.1DL | R402H16 | 350.75 | 19702.75 | 90 | NO |
| R9814 | R402H16 | 47KR2J-2-GP | 63.47334.1DL | R402H16 | 610.5 | 19635.5 | 180 | NO |
| R9815 | R402H16 | 0R2J-2-GP | 63.R0034.1DL | R402H16 | 1833.46 | 17745 | 270 | NO |
| R9816 | R402H16 | 0R2J-2-GP | 63.R0034.1DL | R402H16 | 2177 | 17721 | 270 | NO |
| R9817 | R402H16 | 0R2J-2-GP | 63.R0034.1DL | R402H16 | 1947.5 | 17547.5 | 0 | NO |
| R9818 | R805H24 | 2K2R5F-GP | 64.22015.16L | R805H24 | 1297.25 | 15849.25 | 0 | NO |
| R9819 | R402H16 | 1KR2J-1-GP | 63.10234.1DL | R402H16 | 752.56 | 15853.75 | 180 | NO |
| R9820 | R402H16 | 47KR2J-2-GP | 63.47334.1DL | R402H16 | 1030.25 | 15830.25 | 180 | NO |
| R9821 | R402H16 | 0R2J-2-GP | 63.R0034.1DL | R402H16 | 1931.54 | 13464.88 | 90 | NO |
| R9822 | R402H16 | 0R2J-2-GP | 63.R0034.1DL | R402H16 | 1529.59 | 13523.02 | 90 | NO |
| R9823 | R402H16 | 0R2J-2-GP | 63.R0034.1DL | R402H16 | 1796.54 | 13624.88 | 270 | NO |
| R9826 | R805H24 | 2K2R5F-GP | 64.22015.16L | R805H24 | 1415 | 11859 | 270 | NO |
| R9827 | R402H16 | 1KR2J-1-GP | 63.10234.1DL | R402H16 | 871.75 | 11887.75 | 90 | NO |
| R9828 | R402H16 | 47KR2J-2-GP | 63.47334.1DL | R402H16 | 1136.5 | 11831.5 | 180 | NO |
| R9829 | R402H16 | 0R2J-2-GP | 63.R0034.1DL | R402H16 | 1785 | 9635 | 270 | NO |
| R9830 | R402H16 | 0R2J-2-GP | 63.R0034.1DL | R402H16 | 2056 | 9609.77 | 270 | NO |
| R9831 | R402H16 | 0R2J-2-GP | 63.R0034.1DL | R402H16 | 1679.17 | 9600 | 90 | NO |
| R9832 | R805H24 | 2K2R5F-GP | 64.22015.16L | R805H24 | 1429 | 7806 | 270 | NO |
| R9833 | R402H16 | 1KR2J-1-GP | 63.10234.1DL | R402H16 | 871.75 | 7832.75 | 90 | NO |
| R9834 | R402H16 | 47KR2J-2-GP | 63.47334.1DL | R402H16 | 1136.5 | 7776.5 | 180 | NO |
| R9835 | R402H16 | 0R2J-2-GP | 63.R0034.1DL | R402H16 | 1690 | 5563.3 | 90 | NO |
| R9836 | R402H16 | 0R2J-2-GP | 63.R0034.1DL | R402H16 | 1500 | 5430 | 180 | NO |
| R9837 | R402H16 | 0R2J-2-GP | 63.R0034.1DL | R402H16 | 2110 | 5690 | 270 | NO |
| R9838 | R805H24 | 2K2R5F-GP | 64.22015.16L | R805H24 | 1428 | 3753 | 270 | NO |
| R9839 | R402H16 | 1KR2J-1-GP | 63.10234.1DL | R402H16 | 871.75 | 3777.75 | 90 | NO |
| R9840 | R402H16 | 47KR2J-2-GP | 63.47334.1DL | R402H16 | 1136.5 | 3721.5 | 180 | NO |
| R9841 | R402H16 | 0R2J-2-GP | 63.R0034.1DL | R402H16 | 1920 | 1350 | 90 | NO |
| R9842 | R402H16 | 0R2J-2-GP | 63.R0034.1DL | R402H16 | 1464 | 1380 | 0 | NO |
| R9843 | R402H16 | 0R2J-2-GP | 63.R0034.1DL | R402H16 | 1796.54 | 1474.53 | 270 | NO |
| R9844 | R805H24 | 2K2R5F-GP | 64.22015.16L | R805H24 | 1012 | 16167 | 90 | NO |
| R9845 | R402H16 | 1KR2J-1-GP | 63.10234.1DL | R402H16 | 1568.25 | 16142.25 | 270 | NO |
| R9846 | R402H16 | 47KR2J-2-GP | 63.47334.1DL | R402H16 | 1303.5 | 16208.5 | 0 | NO |
| R9847 | R402H16 | 0R2J-2-GP | 63.R0034.1DL | R402H16 | 866 | 18674 | 90 | NO |
| R9848 | R402H16 | 0R2J-2-GP | 63.R0034.1DL | R402H16 | 861 | 18406 | 90 | NO |
| R9849 | R402H16 | 0R2J-2-GP | 63.R0034.1DL | R402H16 | 1036 | 18399 | 270 | NO |
| R9850 | R805H24 | 2K2R5F-GP | 64.22015.16L | R805H24 | 1013 | 12118 | 90 | NO |
| R9851 | R402H16 | 1KR2J-1-GP | 63.10234.1DL | R402H16 | 1568.25 | 12087.25 | 270 | NO |
| R9852 | R402H16 | 47KR2J-2-GP | 63.47334.1DL | R402H16 | 1303.5 | 12143.5 | 0 | NO |
| R9853 | R402H16 | 0R2J-2-GP | 63.R0034.1DL | R402H16 | 790 | 14700 | 270 | NO |
| R9854 | R402H16 | 0R2J-2-GP | 63.R0034.1DL | R402H16 | 875.89 | 14492.5 | 180 | NO |
| R9855 | R402H16 | 0R2J-2-GP | 63.R0034.1DL | R402H16 | 767.5 | 14491.07 | 180 | NO |
| R9858 | R805H24 | 2K2R5F-GP | 64.22015.16L | R805H24 | 1014 | 8057 | 90 | NO |
| R9859 | R402H16 | 1KR2J-1-GP | 63.10234.1DL | R402H16 | 1585 | 8060 | 0 | NO |
| R9860 | R402H16 | 47KR2J-2-GP | 63.47334.1DL | R402H16 | 1303.5 | 8088.5 | 0 | NO |
| R9861 | R402H16 | 0R2J-2-GP | 63.R0034.1DL | R402H16 | 790 | 10644.88 | 270 | NO |
| R9862 | R402H16 | 0R2J-2-GP | 63.R0034.1DL | R402H16 | 880 | 10445 | 180 | NO |
| R9863 | R402H16 | 0R2J-2-GP | 63.R0034.1DL | R402H16 | 777.5 | 10425.950000000001 | 180 | NO |
| R9864 | R805H24 | 2K2R5F-GP | 64.22015.16L | R805H24 | 1012.25 | 4010.25 | 90 | NO |
| R9865 | R402H16 | 1KR2J-1-GP | 63.10234.1DL | R402H16 | 1564.5 | 3973.5 | 270 | NO |
| R9866 | R402H16 | 47KR2J-2-GP | 63.47334.1DL | R402H16 | 1299.75 | 4029.75 | 0 | NO |
| R9867 | R402H16 | 0R2J-2-GP | 63.R0034.1DL | R402H16 | 790 | 6589.77 | 270 | NO |
| R9868 | R402H16 | 0R2J-2-GP | 63.R0034.1DL | R402H16 | 875.89 | 6382.27 | 180 | NO |
| R9869 | R402H16 | 0R2J-2-GP | 63.R0034.1DL | R402H16 | 767.5 | 6380.84 | 180 | NO |
| R9870 | R805H24 | 2K2R5F-GP | 64.22015.16L | R805H24 | 1566 | 366 | 90 | NO |
| R9871 | R402H16 | 1KR2J-1-GP | 63.10234.1DL | R402H16 | 2073.25 | 237.25 | 270 | NO |
| R9872 | R402H16 | 47KR2J-2-GP | 63.47334.1DL | R402H16 | 1808.5 | 293.5 | 0 | NO |
| R9873 | R402H16 | 0R2J-2-GP | 63.R0034.1DL | R402H16 | 790 | 2534.65 | 270 | NO |
| R9874 | R402H16 | 0R2J-2-GP | 63.R0034.1DL | R402H16 | 875.89 | 2327.15 | 180 | NO |
| R9875 | R402H16 | 0R2J-2-GP | 63.R0034.1DL | R402H16 | 767.5 | 2325.7199999999998 | 180 | NO |
| R9891 | R402H16 | 15KR2F-GP | 64.15025.6DL | R402H16 | 9065 | 17290 | 180 | NO |
| R9892 | R402H16 | 1K82R2F-1-GP | 64.18215.6DL | R402H16 | 9215 | 17775 | 270 | NO |
| R9893 | R402H16 | 1K82R2F-1-GP | 64.18215.6DL | R402H16 | 9215 | 13720 | 270 | NO |
| R9894 | R402H16 | 1K82R2F-1-GP | 64.18215.6DL | R402H16 | 9215 | 9665 | 270 | NO |
| R9895 | R402H16 | 1K82R2F-1-GP | 64.18215.6DL | R402H16 | 9215 | 5610 | 270 | NO |
| R9896 | R402H16 | 1K82R2F-1-GP | 64.18215.6DL | R402H16 | 9215 | 1555 | 270 | NO |
| R9897 | R402H16 | 1K82R2F-1-GP | 64.18215.6DL | R402H16 | 1930 | 17815 | 270 | NO |
| R9898 | R402H16 | 1K82R2F-1-GP | 64.18215.6DL | R402H16 | 1885 | 13730 | 270 | NO |
| R9899 | R402H16 | 1K82R2F-1-GP | 64.18215.6DL | R402H16 | 1940 | 9695 | 270 | NO |
| R9900 | R402H16 | 1K82R2F-1-GP | 64.18215.6DL | R402H16 | 1935 | 5645 | 270 | NO |
| R9901 | R402H16 | 1K82R2F-1-GP | 64.18215.6DL | R402H16 | 1940 | 1580 | 270 | NO |
| R9902 | R402H16 | 1K82R2F-1-GP | 64.18215.6DL | R402H16 | 955 | 18215 | 270 | NO |
| R9903 | R402H16 | 1K82R2F-1-GP | 64.18215.6DL | R402H16 | 945 | 14175 | 270 | NO |
| R9904 | R402H16 | 1K82R2F-1-GP | 64.18215.6DL | R402H16 | 930 | 10105 | 180 | NO |
| R9905 | R402H16 | 1K82R2F-1-GP | 64.18215.6DL | R402H16 | 925 | 6050 | 180 | NO |
| R9906 | R402H16 | 1K82R2F-1-GP | 64.18215.6DL | R402H16 | 945 | 2010 | 270 | NO |
| R9912 | R402H16 | 47KR2J-2-GP | 63.47334.1DL | R402H16 | 8862.5 | 17772.5 | 90 | NO |
| R9913 | R402H16 | 47KR2J-2-GP | 63.47334.1DL | R402H16 | 8856.8799999999992 | 13697 | 90 | NO |
| R9914 | R402H16 | 47KR2J-2-GP | 63.47334.1DL | R402H16 | 8862.5 | 9662.27 | 90 | NO |
| R9915 | R402H16 | 47KR2J-2-GP | 63.47334.1DL | R402H16 | 8862.5 | 5607.15 | 90 | NO |
| R9916 | R402H16 | 47KR2J-2-GP | 63.47334.1DL | R402H16 | 8880 | 1610 | 90 | NO |
| R9917 | R402H16 | 47KR2J-2-GP | 63.47334.1DL | R402H16 | 2177 | 17762 | 270 | NO |
| R9918 | R402H16 | 47KR2J-2-GP | 63.47334.1DL | R402H16 | 1529.59 | 13478.02 | 90 | NO |
| R9919 | R402H16 | 47KR2J-2-GP | 63.47334.1DL | R402H16 | 2056 | 9654.77 | 270 | NO |
| R9920 | R402H16 | 47KR2J-2-GP | 63.47334.1DL | R402H16 | 1545 | 5430 | 180 | NO |
| R9921 | R402H16 | 47KR2J-2-GP | 63.47334.1DL | R402H16 | 1505.57 | 1380 | 0 | NO |
| R9922 | R402H16 | 47KR2J-2-GP | 63.47334.1DL | R402H16 | 861 | 18363 | 90 | NO |
| R9923 | R402H16 | 47KR2J-2-GP | 63.47334.1DL | R402H16 | 835.89 | 14492.5 | 180 | NO |
| R9924 | R402H16 | 47KR2J-2-GP | 63.47334.1DL | R402H16 | 840 | 10445 | 180 | NO |
| R9925 | R402H16 | 47KR2J-2-GP | 63.47334.1DL | R402H16 | 835.89 | 6382.27 | 180 | NO |
| R9926 | R402H16 | 47KR2J-2-GP | 63.47334.1DL | R402H16 | 835.89 | 2327.15 | 180 | NO |
| R9927 | R402H16 | 4K7R2J-2-GP | 63.47234.1DL | R402H16 | 8971.92 | 17908.16 | 270 | NO |
| R9928 | R402H16 | 4K7R2J-2-GP | 63.47234.1DL | R402H16 | 8954 | 17769 | 90 | NO |
| R9929 | R402H16 | 4K7R2J-2-GP | 63.47234.1DL | R402H16 | 8902.1299999999992 | 13781.96 | 180 | NO |
| R9930 | R402H16 | 4K7R2J-2-GP | 63.47234.1DL | R402H16 | 8950.85 | 13713.51 | 90 | NO |
| R9931 | R402H16 | 4K7R2J-2-GP | 63.47234.1DL | R402H16 | 8899.09 | 9756.07 | 180 | NO |
| R9932 | R402H16 | 4K7R2J-2-GP | 63.47234.1DL | R402H16 | 8954.74 | 9659.1299999999992 | 90 | NO |
| R9933 | R402H16 | 4K7R2J-2-GP | 63.47234.1DL | R402H16 | 8976.76 | 5744.22 | 270 | NO |
| R9934 | R402H16 | 4K7R2J-2-GP | 63.47234.1DL | R402H16 | 8952.41 | 5604.08 | 90 | NO |
| R9935 | R402H16 | 4K7R2J-2-GP | 63.47234.1DL | R402H16 | 8888.16 | 1683.54 | 90 | NO |
| R9936 | R402H16 | 4K7R2J-2-GP | 63.47234.1DL | R402H16 | 8969.75 | 1547.24 | 90 | NO |
| R9937 | R402H16 | 4K7R2J-2-GP | 63.47234.1DL | R402H16 | 1691.92 | 17906.919999999998 | 270 | NO |
| R9938 | R402H16 | 4K7R2J-2-GP | 63.47234.1DL | R402H16 | 1700.8 | 17752.28 | 0 | NO |
| R9939 | R402H16 | 4K7R2J-2-GP | 63.47234.1DL | R402H16 | 1693.74 | 13853.23 | 270 | NO |
| R9940 | R402H16 | 4K7R2J-2-GP | 63.47234.1DL | R402H16 | 1640.66 | 13698.27 | 180 | NO |
| R9941 | R402H16 | 4K7R2J-2-GP | 63.47234.1DL | R402H16 | 1665.3 | 9797.2900000000009 | 90 | NO |
| R9942 | R402H16 | 4K7R2J-2-GP | 63.47234.1DL | R402H16 | 1587.46 | 9769.99 | 270 | NO |
| R9943 | R402H16 | 4K7R2J-2-GP | 63.47234.1DL | R402H16 | 1621.44 | 5735.35 | 180 | NO |
| R9944 | R402H16 | 4K7R2J-2-GP | 63.47234.1DL | R402H16 | 1689.95 | 5604.16 | 90 | NO |
| R9945 | R402H16 | 4K7R2J-2-GP | 63.47234.1DL | R402H16 | 1693.56 | 1688.11 | 270 | NO |
| R9946 | R402H16 | 4K7R2J-2-GP | 63.47234.1DL | R402H16 | 1639.94 | 1530.36 | 180 | NO |
| R9947 | R402H16 | 4K7R2J-2-GP | 63.47234.1DL | R402H16 | 718.1 | 18372.7 | 270 | NO |
| R9948 | R402H16 | 4K7R2J-2-GP | 63.47234.1DL | R402H16 | 699.75 | 18233.310000000001 | 270 | NO |
| R9949 | R402H16 | 4K7R2J-2-GP | 63.47234.1DL | R402H16 | 637.97 | 14274.88 | 180 | NO |
| R9950 | R402H16 | 4K7R2J-2-GP | 63.47234.1DL | R402H16 | 658.4 | 14179.1 | 90 | NO |
| R9951 | R402H16 | 4K7R2J-2-GP | 63.47234.1DL | R402H16 | 640.4 | 10219.85 | 180 | NO |
| R9952 | R402H16 | 4K7R2J-2-GP | 63.47234.1DL | R402H16 | 651.95000000000005 | 10124.36 | 90 | NO |
| R9953 | R402H16 | 4K7R2J-2-GP | 63.47234.1DL | R402H16 | 674.14 | 6299.62 | 0 | NO |
| R9954 | R402H16 | 4K7R2J-2-GP | 63.47234.1DL | R402H16 | 636.23 | 6128.7 | 180 | NO |
| R9955 | R402H16 | 4K7R2J-2-GP | 63.47234.1DL | R402H16 | 639.03 | 2108.9499999999998 | 180 | NO |
| R9956 | R402H16 | 4K7R2J-2-GP | 63.47234.1DL | R402H16 | 598.59 | 2066.71 | 0 | NO |
| R9957 | R402H16 | 470R2F-GP | 64.47005.6DL | R402H16 | 3103 | 16942.5 | 180 | NO |
| R9958 | R402H16 | 56R2F-1-GP | 64.56R05.6DL | R402H16 | 3062 | 16942.5 | 0 | NO |
| R9959 | R0201H12 | 100R1F-GP | 64.10005.GIL | R0201H12 | 3286 | 16980.5 | 180 | NO |
| R9960 | R402H16 | 470R2F-GP | 64.47005.6DL | R402H16 | 3103 | 17017.5 | 0 | NO |
| R9961 | R402H16 | 56R2F-1-GP | 64.56R05.6DL | R402H16 | 3062 | 17017.5 | 180 | NO |
| R9962 | R402H16 | 470R2F-GP | 64.47005.6DL | R402H16 | 3093 | 11957.5 | 180 | NO |
| R9963 | R402H16 | 470R2F-GP | 64.47005.6DL | R402H16 | 3093 | 12032.5 | 0 | NO |
| R9964 | R0201H12 | 100R1F-GP | 64.10005.GIL | R0201H12 | 3375 | 11995.5 | 180 | NO |
| R9965 | R402H16 | 56R2F-1-GP | 64.56R05.6DL | R402H16 | 3052 | 12032.5 | 180 | NO |
| R9966 | R402H16 | 56R2F-1-GP | 64.56R05.6DL | R402H16 | 3052 | 11957.5 | 0 | NO |
| R9967 | R402H16 | 470R2F-GP | 64.47005.6DL | R402H16 | 3086 | 8243 | 180 | NO |
| R9968 | R402H16 | 470R2F-GP | 64.47005.6DL | R402H16 | 3086 | 8318 | 0 | NO |
| R9969 | R0201H12 | 100R1F-GP | 64.10005.GIL | R0201H12 | 3368 | 8280.5 | 180 | NO |
| R9970 | R402H16 | 56R2F-1-GP | 64.56R05.6DL | R402H16 | 3045 | 8318 | 180 | NO |
| R9971 | R402H16 | 56R2F-1-GP | 64.56R05.6DL | R402H16 | 3045 | 8243 | 0 | NO |
| R9972 | R402H16 | 470R2F-GP | 64.47005.6DL | R402H16 | 3093 | 3948 | 180 | NO |
| R9973 | R402H16 | 470R2F-GP | 64.47005.6DL | R402H16 | 3093 | 4023 | 0 | NO |
| R9974 | R0201H12 | 100R1F-GP | 64.10005.GIL | R0201H12 | 3378 | 3986 | 180 | NO |
| R9975 | R402H16 | 56R2F-1-GP | 64.56R05.6DL | R402H16 | 3051 | 4023 | 180 | NO |
| R9976 | R402H16 | 56R2F-1-GP | 64.56R05.6DL | R402H16 | 3051 | 3948 | 0 | NO |
| SR945 | R402H16 | 4K7R2F-GP | 64.47015.6DL | R402H16 | 3265 | 17210 | 90 | NO |
| SR946 | R402H16 | 4K7R2F-GP | 64.47015.6DL | R402H16 | 3265 | 17085 | 90 | NO |
| SR947 | R402H16 | 4K7R2F-GP | 64.47015.6DL | R402H16 | 3265 | 17170 | 90 | NO |
| SR948 | R402H16 | 4K7R2F-GP | 64.47015.6DL | R402H16 | 3265 | 12225 | 90 | NO |
| SR949 | R402H16 | 4K7R2F-GP | 64.47015.6DL | R402H16 | 3265 | 12100 | 90 | NO |
| SR950 | R402H16 | 4K7R2F-GP | 64.47015.6DL | R402H16 | 3265 | 12185 | 90 | NO |
| SR951 | R402H16 | 4K7R2F-GP | 64.47015.6DL | R402H16 | 3265 | 8510 | 90 | NO |
| SR952 | R402H16 | 4K7R2F-GP | 64.47015.6DL | R402H16 | 3265 | 8385 | 90 | NO |
| SR953 | R402H16 | 4K7R2F-GP | 64.47015.6DL | R402H16 | 3265 | 8470 | 90 | NO |
| SR954 | R402H16 | 4K7R2F-GP | 64.47015.6DL | R402H16 | 3265 | 4210 | 90 | NO |
| SR955 | R402H16 | 4K7R2F-GP | 64.47015.6DL | R402H16 | 3265 | 4170 | 90 | NO |
| SR956 | R402H16 | 4K7R2F-GP | 64.47015.6DL | R402H16 | 3265 | 4085 | 90 | NO |
| SR964 | R402H16 | 2KR2F-3-GP | 64.20015.6DL | R402H16 | 2905.8 | 5640 | 180 | NO |
| SR965 | R402H16 | 2KR2F-3-GP | 64.20015.6DL | R402H16 | 2984.5 | 5640 | 180 | NO |
| SR966 | R402H16 | 2KR2F-3-GP | 64.20015.6DL | R402H16 | 2785 | 5730 | 90 | NO |
| SR967 | R402H16 | 2KR2F-3-GP | 64.20015.6DL | R402H16 | 2785 | 5650 | 90 | NO |
| SR968 | R402H16 | 2KR2F-3-GP | 64.20015.6DL | R402H16 | 2785 | 5850 | 90 | NO |
| SR969 | R402H16 | 2KR2F-3-GP | 64.20015.6DL | R402H16 | 2785 | 5770 | 90 | NO |
| SR970 | R402H16 | 2KR2F-3-GP | 64.20015.6DL | R402H16 | 2785 | 5970 | 90 | NO |
| SR971 | R402H16 | 2KR2F-3-GP | 64.20015.6DL | R402H16 | 2920 | 6070 | 0 | NO |
| SR972 | R402H16 | 2KR2F-3-GP | 64.20015.6DL | R402H16 | 2785 | 5890 | 90 | NO |
| SR973 | R402H16 | 2KR2F-3-GP | 64.20015.6DL | R402H16 | 2840 | 6070 | 0 | NO |
| SR974 | R402H16 | 2KR2F-3-GP | 64.20015.6DL | R402H16 | 3040 | 6070 | 0 | NO |
| SR975 | R402H16 | 2KR2F-3-GP | 64.20015.6DL | R402H16 | 2960 | 6070 | 0 | NO |
| SR976 | R402H16 | 2KR2F-3-GP | 64.20015.6DL | R402H16 | 3160 | 6070 | 0 | NO |
| SR977 | R402H16 | 2KR2F-3-GP | 64.20015.6DL | R402H16 | 3080 | 6070 | 0 | NO |
| SR978 | R402H16 | 2KR2F-3-GP | 64.20015.6DL | R402H16 | 2785 | 14195 | 90 | NO |
| SR979 | R402H16 | 2KR2F-3-GP | 64.20015.6DL | R402H16 | 2785 | 14315 | 90 | NO |
| SR980 | R402H16 | 2KR2F-3-GP | 64.20015.6DL | R402H16 | 2785 | 14115 | 90 | NO |
| SR981 | R402H16 | 2KR2F-3-GP | 64.20015.6DL | R402H16 | 2785 | 14235 | 90 | NO |
| SR982 | R402H16 | 2KR2F-3-GP | 64.20015.6DL | R402H16 | 2876 | 14430 | 0 | NO |
| SR983 | R402H16 | 2KR2F-3-GP | 64.20015.6DL | R402H16 | 2796.5 | 14430 | 0 | NO |
| SR984 | R402H16 | 2KR2F-3-GP | 64.20015.6DL | R402H16 | 2996 | 14430 | 0 | NO |
| SR985 | R402H16 | 2KR2F-3-GP | 64.20015.6DL | R402H16 | 2916 | 14430 | 0 | NO |
| SR986 | R402H16 | 2KR2F-3-GP | 64.20015.6DL | R402H16 | 3116 | 14430 | 0 | NO |
| SR987 | R402H16 | 2KR2F-3-GP | 64.20015.6DL | R402H16 | 3215 | 14297 | 270 | NO |
| SR988 | R402H16 | 2KR2F-3-GP | 64.20015.6DL | R402H16 | 3036 | 14430 | 0 | NO |
| SR989 | R402H16 | 2KR2F-3-GP | 64.20015.6DL | R402H16 | 3215 | 14377 | 270 | NO |
| SR990 | R402H16 | 2KR2F-3-GP | 64.20015.6DL | R402H16 | 3215 | 14175 | 270 | NO |
| SR991 | R402H16 | 2KR2F-3-GP | 64.20015.6DL | R402H16 | 3215 | 14257 | 270 | NO |
| SR992 | R402H16 | 2KR2F-3-GP | 64.20015.6DL | R402H16 | 3215 | 14054 | 270 | NO |
| SR993 | R402H16 | 2KR2F-3-GP | 64.20015.6DL | R402H16 | 3215 | 14135 | 270 | NO |
| SR1046 | R402H16 | 4K7R2F-GP | 64.47015.6DL | R402H16 | 3130 | 5640 | 0 | NO |
| SR1047 | R402H16 | 4K7R2F-GP | 64.47015.6DL | R402H16 | 3275 | 5970 | 90 | NO |
| SR1049 | R402H16 | 4K7R2F-GP | 64.47015.6DL | R402H16 | 3275 | 5930 | 270 | NO |
| SR1050 | R402H16 | 4K7R2F-GP | 64.47015.6DL | R402H16 | 3035 | 13940 | 0 | NO |
| SR1051 | R402H16 | 4K7R2F-GP | 64.47015.6DL | R402H16 | 2785 | 14075 | 270 | NO |
| SR1052 | R402H16 | 4K7R2F-GP | 64.47015.6DL | R402H16 | 3155 | 13940 | 180 | NO |
| SR1091 | R402H16 | 4K7R2F-GP | 64.47015.6DL | R402H16 | 8496 | 19452 | 90 | NO |
| SR1092 | R402H16 | 4K7R2F-GP | 64.47015.6DL | R402H16 | 8496 | 19497 | 270 | NO |
| SR1093 | R402H16 | 4K7R2F-GP | 64.47015.6DL | R402H16 | 8456 | 15495 | 0 | NO |
| SR1094 | R402H16 | 4K7R2F-GP | 64.47015.6DL | R402H16 | 8555 | 15495 | 180 | NO |
| SR1095 | R402H16 | 4K7R2F-GP | 64.47015.6DL | R402H16 | 8446 | 11439 | 0 | NO |
| SR1096 | R402H16 | 4K7R2F-GP | 64.47015.6DL | R402H16 | 8545 | 11439 | 180 | NO |
| SR1097 | R402H16 | 4K7R2F-GP | 64.47015.6DL | R402H16 | 8462 | 7385 | 0 | NO |
| SR1098 | R402H16 | 4K7R2F-GP | 64.47015.6DL | R402H16 | 8561 | 7385 | 180 | NO |
| SR1099 | R402H16 | 4K7R2F-GP | 64.47015.6DL | R402H16 | 8440.5 | 3325 | 0 | NO |
| SR1100 | R402H16 | 4K7R2F-GP | 64.47015.6DL | R402H16 | 8562 | 3325 | 180 | NO |
| SR1101 | R402H16 | 4K7R2F-GP | 64.47015.6DL | R402H16 | 1207 | 19439 | 90 | NO |
| SR1102 | R402H16 | 4K7R2F-GP | 64.47015.6DL | R402H16 | 1265 | 19455 | 180 | NO |
| SR1103 | R402H16 | 4K7R2F-GP | 64.47015.6DL | R402H16 | 1108 | 15437 | 90 | NO |
| SR1104 | R402H16 | 4K7R2F-GP | 64.47015.6DL | R402H16 | 1108 | 15482 | 270 | NO |
| SR1105 | R402H16 | 4K7R2F-GP | 64.47015.6DL | R402H16 | 1179 | 11443 | 0 | NO |
| SR1106 | R402H16 | 4K7R2F-GP | 64.47015.6DL | R402H16 | 1224 | 11443 | 180 | NO |
| SR1107 | R402H16 | 4K7R2F-GP | 64.47015.6DL | R402H16 | 1179.45 | 7389.17 | 0 | NO |
| SR1108 | R402H16 | 4K7R2F-GP | 64.47015.6DL | R402H16 | 1224.45 | 7389.17 | 180 | NO |
| SR1109 | R402H16 | 4K7R2F-GP | 64.47015.6DL | R402H16 | 1142.95 | 3333.17 | 0 | NO |
| SR1110 | R402H16 | 4K7R2F-GP | 64.47015.6DL | R402H16 | 1264.45 | 3333.17 | 180 | NO |
| SR1111 | R402H16 | 4K7R2F-GP | 64.47015.6DL | R402H16 | 1269 | 16595 | 180 | NO |
| SR1112 | R402H16 | 4K7R2F-GP | 64.47015.6DL | R402H16 | 1170 | 16595 | 0 | NO |
| SR1113 | R402H16 | 4K7R2F-GP | 64.47015.6DL | R402H16 | 1260 | 12538 | 180 | NO |
| SR1114 | R402H16 | 4K7R2F-GP | 64.47015.6DL | R402H16 | 1215 | 12538 | 0 | NO |
| SR1115 | R402H16 | 4K7R2F-GP | 64.47015.6DL | R402H16 | 1268 | 8473 | 180 | NO |
| SR1116 | R402H16 | 4K7R2F-GP | 64.47015.6DL | R402H16 | 1222.51 | 8472.4599999999991 | 0 | NO |
| SR1117 | R402H16 | 4K7R2F-GP | 64.47015.6DL | R402H16 | 1253 | 4428 | 180 | NO |
| SR1118 | R402H16 | 4K7R2F-GP | 64.47015.6DL | R402H16 | 1208 | 4428 | 0 | NO |
| SR1119 | R402H16 | 4K7R2F-GP | 64.47015.6DL | R402H16 | 1257 | 496 | 0 | NO |
| SR1120 | R402H16 | 4K7R2F-GP | 64.47015.6DL | R402H16 | 1216 | 496 | 180 | NO |
| SR1121 | R402H16 | 4K7R2F-GP | 64.47015.6DL | R402H16 | 8635 | 17700 | 90 | NO |
| SR1122 | R402H16 | 4K7R2J-2-GP | 63.47234.1DL | R402H16 | 8988 | 17710 | 180 | NO |
| SR1123 | R402H16 | 4K7R2F-GP | 64.47015.6DL | R402H16 | 8635 | 13644.88 | 90 | NO |
| SR1124 | R402H16 | 4K7R2J-2-GP | 63.47234.1DL | R402H16 | 8987.48 | 13654.88 | 180 | NO |
| SR1125 | R402H16 | 4K7R2F-GP | 64.47015.6DL | R402H16 | 8635 | 9589.77 | 90 | NO |
| SR1126 | R402H16 | 4K7R2J-2-GP | 63.47234.1DL | R402H16 | 8986.48 | 9599.77 | 180 | NO |
| SR1127 | R402H16 | 4K7R2F-GP | 64.47015.6DL | R402H16 | 8635 | 5534.65 | 90 | NO |
| SR1128 | R402H16 | 4K7R2J-2-GP | 63.47234.1DL | R402H16 | 8987.5400000000009 | 5544.65 | 180 | NO |
| SR1129 | R402H16 | 4K7R2F-GP | 64.47015.6DL | R402H16 | 8669.61 | 1576.61 | 0 | NO |
| SR1130 | R402H16 | 4K7R2J-2-GP | 63.47234.1DL | R402H16 | 8996.48 | 1489.53 | 180 | NO |
| SR1131 | R402H16 | 4K7R2F-GP | 64.47015.6DL | R402H16 | 2466 | 17699 | 270 | NO |
| SR1132 | R402H16 | 4K7R2J-2-GP | 63.47234.1DL | R402H16 | 2001.98 | 17605 | 0 | NO |
| SR1133 | R402H16 | 4K7R2F-GP | 64.47015.6DL | R402H16 | 1383.75 | 13780.1 | 270 | NO |
| SR1134 | R402H16 | 4K7R2J-2-GP | 63.47234.1DL | R402H16 | 1704.02 | 13649.88 | 180 | NO |
| SR1135 | R402H16 | 4K7R2F-GP | 64.47015.6DL | R402H16 | 2295 | 9514.77 | 180 | NO |
| SR1136 | R402H16 | 4K7R2J-2-GP | 63.47234.1DL | R402H16 | 1780 | 9545 | 0 | NO |
| SR1137 | R402H16 | 4K7R2F-GP | 64.47015.6DL | R402H16 | 1220.25 | 5713.75 | 0 | NO |
| SR1138 | R402H16 | 4K7R2J-2-GP | 63.47234.1DL | R402H16 | 2020 | 5690 | 90 | NO |
| SR1139 | R402H16 | 4K7R2F-GP | 64.47015.6DL | R402H16 | 1343.75 | 1624.75 | 270 | NO |
| SR1140 | R402H16 | 4K7R2J-2-GP | 63.47234.1DL | R402H16 | 1704.02 | 1494.53 | 180 | NO |
| SR1141 | R402H16 | 4K7R2F-GP | 64.47015.6DL | R402H16 | 771 | 18479 | 0 | NO |
| SR1142 | R402H16 | 4K7R2J-2-GP | 63.47234.1DL | R402H16 | 961 | 18399 | 90 | NO |
| SR1143 | R402H16 | 4K7R2F-GP | 64.47015.6DL | R402H16 | 945 | 14310 | 270 | NO |
| SR1144 | R402H16 | 4K7R2J-2-GP | 63.47234.1DL | R402H16 | 767.5 | 14568.5 | 0 | NO |
| SR1145 | R402H16 | 4K7R2F-GP | 64.47015.6DL | R402H16 | 945 | 10254.879999999999 | 270 | NO |
| SR1146 | R402H16 | 4K7R2J-2-GP | 63.47234.1DL | R402H16 | 777.5 | 10511.36 | 0 | NO |
| SR1147 | R402H16 | 4K7R2F-GP | 64.47015.6DL | R402H16 | 945 | 6199.77 | 270 | NO |
| SR1148 | R402H16 | 4K7R2J-2-GP | 63.47234.1DL | R402H16 | 802.5 | 6452.27 | 270 | NO |
| SR1149 | R402H16 | 4K7R2F-GP | 64.47015.6DL | R402H16 | 945 | 2144.65 | 270 | NO |
| SR1150 | R402H16 | 4K7R2J-2-GP | 63.47234.1DL | R402H16 | 802.5 | 2397.15 | 270 | NO |
| SR1151 | R402H16 | 4K7R2F-GP | 64.47015.6DL | R402H16 | 3275 | 6010 | 270 | NO |
| SR1152 | R402H16 | 4K7R2F-GP | 64.47015.6DL | R402H16 | 3175 | 5640 | 180 | NO |
| SR1153 | R402H16 | 4K7R2F-GP | 64.47015.6DL | R402H16 | 3275 | 5890 | 90 | NO |
| SR1154 | R402H16 | 4K7R2F-GP | 64.47015.6DL | R402H16 | 3075 | 13940 | 180 | NO |
| SR1155 | R402H16 | 4K7R2F-GP | 64.47015.6DL | R402H16 | 2785 | 14035 | 90 | NO |
| SR1156 | R402H16 | 4K7R2F-GP | 64.47015.6DL | R402H16 | 3115 | 13940 | 0 | NO |
| TP1 | TPAD28 | TPAD28-2-GP | ZZ.PAD28.XXX | TPAD28 | 9760 | 16360 | 0 | NO |
| TP2 | TPAD28 | TPAD28-2-GP | ZZ.PAD28.XXX | TPAD28 | 9695 | 16765 | 0 | NO |
| TP3 | TPAD28 | TPAD28-2-GP | ZZ.PAD28.XXX | TPAD28 | 9690 | 16415 | 0 | NO |
| TP4 | TPAD32 | TPAD32-GP | ZZ.0TPAD.191 | TPAD32 | 8105 | 17970 | 0 | NO |
| TP5 | TPAD32 | TPAD32-GP | ZZ.0TPAD.191 | TPAD32 | 1545 | 5360 | 0 | NO |
| TP6 | TPAD32 | TPAD32-GP | ZZ.0TPAD.191 | TPAD32 | 8105 | 1830 | 0 | NO |
| TP7 | TPAD32 | TPAD32-GP | ZZ.0TPAD.191 | TPAD32 | 1040 | 14820 | 0 | NO |
| TP150 | TPAD32 | TPAD32-GP | ZZ.0TPAD.191 | TPAD32 | 3580 | 760 | 90 | NO |
| U9 | SOIC8H79 | P2003EVG-GP | 84.02003.A37 | SOIC8H79 | 8124.39 | 19416.07 | 270 | NO |
| U10 | SOIC8H79 | P2003EVG-GP | 84.02003.A37 | SOIC8H79 | 8455 | 15665 | 270 | NO |
| U11 | SOIC8H79 | P2003EVG-GP | 84.02003.A37 | SOIC8H79 | 8455 | 11610 | 270 | NO |
| U12 | SOIC8H79 | P2003EVG-GP | 84.02003.A37 | SOIC8H79 | 8455 | 7555 | 270 | NO |
| U13 | SOIC8H79 | P2003EVG-GP | 84.02003.A37 | SOIC8H79 | 8455 | 3500 | 270 | NO |
| U14 | SOIC8H79 | P2003EVG-GP | 84.02003.A37 | SOIC8H79 | 895 | 19415 | 270 | NO |
| U15 | SOIC8H79 | P2003EVG-GP | 84.02003.A37 | SOIC8H79 | 1167 | 15616 | 270 | NO |
| U16 | SOIC8H79 | P2003EVG-GP | 84.02003.A37 | SOIC8H79 | 1172 | 11614 | 270 | NO |
| U17 | SOIC8H79 | P2003EVG-GP | 84.02003.A37 | SOIC8H79 | 1172 | 7555 | 270 | NO |
| U18 | SOIC8H79 | P2003EVG-GP | 84.02003.A37 | SOIC8H79 | 1172 | 3500 | 270 | NO |
| U19 | SOIC8H79 | P2003EVG-GP | 84.02003.A37 | SOIC8H79 | 1284 | 16421 | 90 | NO |
| U20 | SOIC8H79 | P2003EVG-GP | 84.02003.A37 | SOIC8H79 | 1272 | 12366 | 90 | NO |
| U21 | SOIC8H79 | P2003EVG-GP | 84.02003.A37 | SOIC8H79 | 1269 | 8311 | 90 | NO |
| U22 | SOIC8H79 | P2003EVG-GP | 84.02003.A37 | SOIC8H79 | 1269 | 4256 | 90 | NO |
| U23 | SOIC8H79 | P2003EVG-GP | 84.02003.A37 | SOIC8H79 | 1755 | 515 | 90 | NO |
| U47 | MSOP8-1H44 | TMP75AIDGKR-GP | 74.00075.B79 | MSOP8-1H44 | 8287.4 | 18070.87 | 270 | NO |
| U48 | MSOP8-1H44 | TMP75AIDGKR-GP | 74.00075.B79 | MSOP8-1H44 | 8287.4 | 1929.13 | 270 | NO |
| U49 | MSOP8-1H44 | TMP75AIDGKR-GP | 74.00075.B79 | MSOP8-1H44 | 1220.47 | 14921.26 | 270 | NO |
| U50 | SSOIC8-1H44 | 24LC64T-I-GP | 72.02464.00Q | SSOIC8-1H44 | 2770 | 17635 | 180 | NO |
| U51 | MSOP8-1H44 | TMP75AIDGKR-GP | 74.00075.B79 | MSOP8-1H44 | 1732.28 | 5433.07 | 270 | NO |
| U53 | MSOP10H44 | ADS1015IDGSR-GP | 74.01015.049 | MSOP10H44 | 3585 | 965 | 0 | NO |
| U197 | SC70-5H44 | SN74LVC1G08DCKR-GP | 73.01G08.L03 | SC70-5H44 | 8945 | 17595 | 90 | NO |
| U198 | SC70-5H44 | SN74LVC1G08DCKR-GP | 73.01G08.L03 | SC70-5H44 | 8945 | 13539.88 | 90 | NO |
| U199 | SC70-5H44 | SN74LVC1G08DCKR-GP | 73.01G08.L03 | SC70-5H44 | 8945 | 9484.77 | 90 | NO |
| U200 | SC70-5H44 | SN74LVC1G08DCKR-GP | 73.01G08.L03 | SC70-5H44 | 8945 | 5429.65 | 90 | NO |
| U201 | SC70-5H44 | SN74LVC1G08DCKR-GP | 73.01G08.L03 | SC70-5H44 | 8955 | 1374.53 | 90 | NO |
| U202 | SC70-5H44 | SN74LVC1G08DCKR-GP | 73.01G08.L03 | SC70-5H44 | 2043.46 | 17720 | 270 | NO |
| U203 | SC70-5H44 | SN74LVC1G08DCKR-GP | 73.01G08.L03 | SC70-5H44 | 1661.54 | 13539.88 | 90 | NO |
| U204 | SC70-5H44 | SN74LVC1G08DCKR-GP | 73.01G08.L03 | SC70-5H44 | 1900 | 9530 | 180 | NO |
| U205 | SC70-5H44 | SN74LVC1G08DCKR-GP | 73.01G08.L03 | SC70-5H44 | 1535 | 5600 | 180 | NO |
| U206 | SC70-5H44 | SN74LVC1G08DCKR-GP | 73.01G08.L03 | SC70-5H44 | 1661.54 | 1384.53 | 90 | NO |
| U207 | SC70-5H44 | SN74LVC1G08DCKR-GP | 73.01G08.L03 | SC70-5H44 | 882 | 18504 | 180 | NO |
| U208 | SC70-5H44 | SN74LVC1G08DCKR-GP | 73.01G08.L03 | SC70-5H44 | 944.81 | 14609.58 | 270 | NO |
| U209 | SC70-5H44 | SN74LVC1G08DCKR-GP | 73.01G08.L03 | SC70-5H44 | 944.81 | 10554.46 | 270 | NO |
| U210 | SC70-5H44 | SN74LVC1G08DCKR-GP | 73.01G08.L03 | SC70-5H44 | 944.81 | 6499.35 | 270 | NO |
| U211 | SC70-5H44 | SN74LVC1G08DCKR-GP | 73.01G08.L03 | SC70-5H44 | 944.81 | 2444.23 | 270 | NO |
